FILE_TYPE = MACRO_DRAWING;
SET COLOR_WIRE YELLOW;
SET COLOR_PROP ORANGE;
SET COLOR_DOT WHITE;
SET COLOR_ARC YELLOW;
SET COLOR_BODY GREEN;
SET COLOR_NOTE PURPLE;
SET PROP_DISPLAY VALUE;
SET PAGE_NUMBER P49;
FORCEADD GENOA_SP5..11
(-4775 5000);
FORCEPROP 1 LAST LOCATION U26
J 0
(-5870 6256);
DISPLAY 0.489362 (-5870 6256);
PAINT SKYBLUE (-5870 6256);
FORCEPROP 0 LAST $SEC 11
J 0
(-5850 6300);
DISPLAY 0.680851 (-5850 6300);
PAINT MONO (-5850 6300);
DISPLAY INVISIBLE (-5850 6300);
FORCEPROP 0 LAST CDS_SEC 11
J 0
(-5875 6225);
DISPLAY 1.021277 (-5875 6225);
DISPLAY INVISIBLE (-5875 6225);
FORCEPROP 0 LASTPIN (-6025 5700) $PN M40
J 2
(-6035 5710);
DISPLAY 0.489362 (-6035 5710);
PAINT MONO (-6035 5710);
FORCEPROP 0 LASTPIN (-6025 5600) $PN K40
J 2
(-6035 5610);
DISPLAY 0.489362 (-6035 5610);
PAINT MONO (-6035 5610);
FORCEPROP 0 LASTPIN (-6025 5500) $PN H40
J 2
(-6035 5510);
DISPLAY 0.489362 (-6035 5510);
PAINT MONO (-6035 5510);
FORCEPROP 0 LASTPIN (-6025 5400) $PN L43
J 2
(-6035 5410);
DISPLAY 0.489362 (-6035 5410);
PAINT MONO (-6035 5410);
FORCEPROP 0 LASTPIN (-6025 5300) $PN G43
J 2
(-6035 5310);
DISPLAY 0.489362 (-6035 5310);
PAINT MONO (-6035 5310);
FORCEPROP 0 LASTPIN (-6025 5200) $PN J43
J 2
(-6035 5210);
DISPLAY 0.489362 (-6035 5210);
PAINT MONO (-6035 5210);
FORCEPROP 0 LASTPIN (-6025 5100) $PN L46
J 2
(-6035 5110);
DISPLAY 0.489362 (-6035 5110);
PAINT MONO (-6035 5110);
FORCEPROP 0 LASTPIN (-6025 5000) $PN G46
J 2
(-6035 5010);
DISPLAY 0.489362 (-6035 5010);
PAINT MONO (-6035 5010);
FORCEPROP 0 LASTPIN (-6025 4900) $PN J46
J 2
(-6035 4910);
DISPLAY 0.489362 (-6035 4910);
PAINT MONO (-6035 4910);
FORCEPROP 0 LASTPIN (-6025 4800) $PN L49
J 2
(-6035 4810);
DISPLAY 0.489362 (-6035 4810);
PAINT MONO (-6035 4810);
FORCEPROP 0 LASTPIN (-6025 4700) $PN G49
J 2
(-6035 4710);
DISPLAY 0.489362 (-6035 4710);
PAINT MONO (-6035 4710);
FORCEPROP 0 LASTPIN (-6025 4600) $PN J49
J 2
(-6035 4610);
DISPLAY 0.489362 (-6035 4610);
PAINT MONO (-6035 4610);
FORCEPROP 0 LASTPIN (-6025 4500) $PN L52
J 2
(-6035 4510);
DISPLAY 0.489362 (-6035 4510);
PAINT MONO (-6035 4510);
FORCEPROP 0 LASTPIN (-6025 4400) $PN G52
J 2
(-6035 4410);
DISPLAY 0.489362 (-6035 4410);
PAINT MONO (-6035 4410);
FORCEPROP 0 LASTPIN (-6025 4300) $PN J52
J 2
(-6035 4310);
DISPLAY 0.489362 (-6035 4310);
PAINT MONO (-6035 4310);
FORCEPROP 0 LASTPIN (-6025 4200) $PN N52
J 2
(-6035 4210);
DISPLAY 0.489362 (-6035 4210);
PAINT MONO (-6035 4210);
FORCEPROP 0 LASTPIN (-6025 5750) $PN M41
J 2
(-6035 5760);
DISPLAY 0.489362 (-6035 5760);
PAINT MONO (-6035 5760);
FORCEPROP 0 LASTPIN (-6025 5650) $PN K41
J 2
(-6035 5660);
DISPLAY 0.489362 (-6035 5660);
PAINT MONO (-6035 5660);
FORCEPROP 0 LASTPIN (-6025 5550) $PN H41
J 2
(-6035 5560);
DISPLAY 0.489362 (-6035 5560);
PAINT MONO (-6035 5560);
FORCEPROP 0 LASTPIN (-6025 5450) $PN L44
J 2
(-6035 5460);
DISPLAY 0.489362 (-6035 5460);
PAINT MONO (-6035 5460);
FORCEPROP 0 LASTPIN (-6025 5350) $PN G44
J 2
(-6035 5360);
DISPLAY 0.489362 (-6035 5360);
PAINT MONO (-6035 5360);
FORCEPROP 0 LASTPIN (-6025 5250) $PN J44
J 2
(-6035 5260);
DISPLAY 0.489362 (-6035 5260);
PAINT MONO (-6035 5260);
FORCEPROP 0 LASTPIN (-6025 5150) $PN L47
J 2
(-6035 5160);
DISPLAY 0.489362 (-6035 5160);
PAINT MONO (-6035 5160);
FORCEPROP 0 LASTPIN (-6025 5050) $PN G47
J 2
(-6035 5060);
DISPLAY 0.489362 (-6035 5060);
PAINT MONO (-6035 5060);
FORCEPROP 0 LASTPIN (-6025 4950) $PN J47
J 2
(-6035 4960);
DISPLAY 0.489362 (-6035 4960);
PAINT MONO (-6035 4960);
FORCEPROP 0 LASTPIN (-6025 4850) $PN L50
J 2
(-6035 4860);
DISPLAY 0.489362 (-6035 4860);
PAINT MONO (-6035 4860);
FORCEPROP 0 LASTPIN (-6025 4750) $PN G50
J 2
(-6035 4760);
DISPLAY 0.489362 (-6035 4760);
PAINT MONO (-6035 4760);
FORCEPROP 0 LASTPIN (-6025 4650) $PN J50
J 2
(-6035 4660);
DISPLAY 0.489362 (-6035 4660);
PAINT MONO (-6035 4660);
FORCEPROP 0 LASTPIN (-6025 4550) $PN L53
J 2
(-6035 4560);
DISPLAY 0.489362 (-6035 4560);
PAINT MONO (-6035 4560);
FORCEPROP 0 LASTPIN (-6025 4450) $PN G53
J 2
(-6035 4460);
DISPLAY 0.489362 (-6035 4460);
PAINT MONO (-6035 4460);
FORCEPROP 0 LASTPIN (-6025 4350) $PN J53
J 2
(-6035 4360);
DISPLAY 0.489362 (-6035 4360);
PAINT MONO (-6035 4360);
FORCEPROP 0 LASTPIN (-6025 4250) $PN N53
J 2
(-6035 4260);
DISPLAY 0.489362 (-6035 4260);
PAINT MONO (-6035 4260);
FORCEPROP 0 LASTPIN (-3525 5700) $PN AF41
J 0
(-3515 5710);
DISPLAY 0.489362 (-3515 5710);
PAINT MONO (-3515 5710);
FORCEPROP 0 LASTPIN (-3525 5600) $PN AD41
J 0
(-3515 5610);
DISPLAY 0.489362 (-3515 5610);
PAINT MONO (-3515 5610);
FORCEPROP 0 LASTPIN (-3525 5500) $PN AB41
J 0
(-3515 5510);
DISPLAY 0.489362 (-3515 5510);
PAINT MONO (-3515 5510);
FORCEPROP 0 LASTPIN (-3525 5400) $PN AG44
J 0
(-3515 5410);
DISPLAY 0.489362 (-3515 5410);
PAINT MONO (-3515 5410);
FORCEPROP 0 LASTPIN (-3525 5300) $PN AA44
J 0
(-3515 5310);
DISPLAY 0.489362 (-3515 5310);
PAINT MONO (-3515 5310);
FORCEPROP 0 LASTPIN (-3525 5200) $PN AC44
J 0
(-3515 5210);
DISPLAY 0.489362 (-3515 5210);
PAINT MONO (-3515 5210);
FORCEPROP 0 LASTPIN (-3525 5100) $PN AE44
J 0
(-3515 5110);
DISPLAY 0.489362 (-3515 5110);
PAINT MONO (-3515 5110);
FORCEPROP 0 LASTPIN (-3525 5000) $PN AG47
J 0
(-3515 5010);
DISPLAY 0.489362 (-3515 5010);
PAINT MONO (-3515 5010);
FORCEPROP 0 LASTPIN (-3525 4900) $PN AC47
J 0
(-3515 4910);
DISPLAY 0.489362 (-3515 4910);
PAINT MONO (-3515 4910);
FORCEPROP 0 LASTPIN (-3525 4800) $PN AE47
J 0
(-3515 4810);
DISPLAY 0.489362 (-3515 4810);
PAINT MONO (-3515 4810);
FORCEPROP 0 LASTPIN (-3525 4700) $PN AG50
J 0
(-3515 4710);
DISPLAY 0.489362 (-3515 4710);
PAINT MONO (-3515 4710);
FORCEPROP 0 LASTPIN (-3525 4600) $PN AC50
J 0
(-3515 4610);
DISPLAY 0.489362 (-3515 4610);
PAINT MONO (-3515 4610);
FORCEPROP 0 LASTPIN (-3525 4500) $PN AE50
J 0
(-3515 4510);
DISPLAY 0.489362 (-3515 4510);
PAINT MONO (-3515 4510);
FORCEPROP 0 LASTPIN (-3525 4400) $PN AG53
J 0
(-3515 4410);
DISPLAY 0.489362 (-3515 4410);
PAINT MONO (-3515 4410);
FORCEPROP 0 LASTPIN (-3525 4300) $PN AC53
J 0
(-3515 4310);
DISPLAY 0.489362 (-3515 4310);
PAINT MONO (-3515 4310);
FORCEPROP 0 LASTPIN (-3525 4200) $PN AE53
J 0
(-3515 4210);
DISPLAY 0.489362 (-3515 4210);
PAINT MONO (-3515 4210);
FORCEPROP 0 LASTPIN (-3525 5750) $PN AF40
J 0
(-3515 5760);
DISPLAY 0.489362 (-3515 5760);
PAINT MONO (-3515 5760);
FORCEPROP 0 LASTPIN (-3525 5650) $PN AD40
J 0
(-3515 5660);
DISPLAY 0.489362 (-3515 5660);
PAINT MONO (-3515 5660);
FORCEPROP 0 LASTPIN (-3525 5550) $PN AB40
J 0
(-3515 5560);
DISPLAY 0.489362 (-3515 5560);
PAINT MONO (-3515 5560);
FORCEPROP 0 LASTPIN (-3525 5450) $PN AG43
J 0
(-3515 5460);
DISPLAY 0.489362 (-3515 5460);
PAINT MONO (-3515 5460);
FORCEPROP 0 LASTPIN (-3525 5350) $PN AA43
J 0
(-3515 5360);
DISPLAY 0.489362 (-3515 5360);
PAINT MONO (-3515 5360);
FORCEPROP 0 LASTPIN (-3525 5250) $PN AC43
J 0
(-3515 5260);
DISPLAY 0.489362 (-3515 5260);
PAINT MONO (-3515 5260);
FORCEPROP 0 LASTPIN (-3525 5150) $PN AE43
J 0
(-3515 5160);
DISPLAY 0.489362 (-3515 5160);
PAINT MONO (-3515 5160);
FORCEPROP 0 LASTPIN (-3525 5050) $PN AG46
J 0
(-3515 5060);
DISPLAY 0.489362 (-3515 5060);
PAINT MONO (-3515 5060);
FORCEPROP 0 LASTPIN (-3525 4950) $PN AC46
J 0
(-3515 4960);
DISPLAY 0.489362 (-3515 4960);
PAINT MONO (-3515 4960);
FORCEPROP 0 LASTPIN (-3525 4850) $PN AE46
J 0
(-3515 4860);
DISPLAY 0.489362 (-3515 4860);
PAINT MONO (-3515 4860);
FORCEPROP 0 LASTPIN (-3525 4750) $PN AG49
J 0
(-3515 4760);
DISPLAY 0.489362 (-3515 4760);
PAINT MONO (-3515 4760);
FORCEPROP 0 LASTPIN (-3525 4650) $PN AC49
J 0
(-3515 4660);
DISPLAY 0.489362 (-3515 4660);
PAINT MONO (-3515 4660);
FORCEPROP 0 LASTPIN (-3525 4550) $PN AE49
J 0
(-3515 4560);
DISPLAY 0.489362 (-3515 4560);
PAINT MONO (-3515 4560);
FORCEPROP 0 LASTPIN (-3525 4450) $PN AG52
J 0
(-3515 4460);
DISPLAY 0.489362 (-3515 4460);
PAINT MONO (-3515 4460);
FORCEPROP 0 LASTPIN (-3525 4350) $PN AC52
J 0
(-3515 4360);
DISPLAY 0.489362 (-3515 4360);
PAINT MONO (-3515 4360);
FORCEPROP 0 LASTPIN (-3525 4250) $PN AE52
J 0
(-3515 4260);
DISPLAY 0.489362 (-3515 4260);
PAINT MONO (-3515 4260);
FORCEPROP 2 LAST PART_TYPE SMLF
J 0
(-5875 6175);
DISPLAY 1.021277 (-5875 6175);
FORCEPROP 1 LAST MATERIAL IO
J 0
(-5870 5982);
DISPLAY 0.489362 (-5870 5982);
PAINT SKYBLUE (-5870 5982);
FORCEPROP 2 LAST VALUE SOCKET6096_13568-001
J 0
(-5875 6075);
DISPLAY 0.489362 (-5875 6075);
PAINT SKYBLUE (-5875 6075);
FORCEPROP 1 LAST PART_NUMBER DGA^6000030
J 0
(-5870 6109);
DISPLAY 0.489362 (-5870 6109);
PAINT SKYBLUE (-5870 6109);
FORCEPROP 2 LAST CDS_LIB pure_quanta
J 0
(-4775 5000);
DISPLAY INVISIBLE (-4775 5000);
FORCEPROP 1 LAST NEEDS_NO_SIZE TRUE
J 0
(-4775 5000);
DISPLAY 0.723404 (-4775 5000);
PAINT GREEN (-4775 5000);
DISPLAY INVISIBLE (-4775 5000);
FORCEPROP 1 LAST CDS_LMAN_SYM_OUTLINE -1100,950,1100,-950
J 0
(-4775 5000);
DISPLAY 0.468085 (-4775 5000);
PAINT GREEN (-4775 5000);
DISPLAY INVISIBLE (-4775 5000);
FORCEPROP 1 LAST PATH I213
J 0
(-4775 5000);
DISPLAY 0.723404 (-4775 5000);
PAINT GREEN (-4775 5000);
DISPLAY INVISIBLE (-4775 5000);
FORCEADD GENOA_SP5..12
(-4750 2275);
FORCEPROP 1 LAST LOCATION U26
J 0
(-5845 3531);
DISPLAY 0.489362 (-5845 3531);
PAINT SKYBLUE (-5845 3531);
FORCEPROP 0 LAST $SEC 12
J 0
(-5825 3575);
DISPLAY 0.680851 (-5825 3575);
PAINT MONO (-5825 3575);
DISPLAY INVISIBLE (-5825 3575);
FORCEPROP 0 LAST CDS_SEC 12
J 0
(-5850 3500);
DISPLAY 1.021277 (-5850 3500);
DISPLAY INVISIBLE (-5850 3500);
FORCEPROP 0 LASTPIN (-6000 2975) $PN V40
J 2
(-6010 2985);
DISPLAY 0.489362 (-6010 2985);
PAINT MONO (-6010 2985);
FORCEPROP 0 LASTPIN (-6000 2875) $PN T40
J 2
(-6010 2885);
DISPLAY 0.489362 (-6010 2885);
PAINT MONO (-6010 2885);
FORCEPROP 0 LASTPIN (-6000 2775) $PN P40
J 2
(-6010 2785);
DISPLAY 0.489362 (-6010 2785);
PAINT MONO (-6010 2785);
FORCEPROP 0 LASTPIN (-6000 2675) $PN U43
J 2
(-6010 2685);
DISPLAY 0.489362 (-6010 2685);
PAINT MONO (-6010 2685);
FORCEPROP 0 LASTPIN (-6000 2575) $PN N43
J 2
(-6010 2585);
DISPLAY 0.489362 (-6010 2585);
PAINT MONO (-6010 2585);
FORCEPROP 0 LASTPIN (-6000 2475) $PN R43
J 2
(-6010 2485);
DISPLAY 0.489362 (-6010 2485);
PAINT MONO (-6010 2485);
FORCEPROP 0 LASTPIN (-6000 2375) $PN U46
J 2
(-6010 2385);
DISPLAY 0.489362 (-6010 2385);
PAINT MONO (-6010 2385);
FORCEPROP 0 LASTPIN (-6000 2275) $PN N46
J 2
(-6010 2285);
DISPLAY 0.489362 (-6010 2285);
PAINT MONO (-6010 2285);
FORCEPROP 0 LASTPIN (-6000 2175) $PN R46
J 2
(-6010 2185);
DISPLAY 0.489362 (-6010 2185);
PAINT MONO (-6010 2185);
FORCEPROP 0 LASTPIN (-6000 2075) $PN W49
J 2
(-6010 2085);
DISPLAY 0.489362 (-6010 2085);
PAINT MONO (-6010 2085);
FORCEPROP 0 LASTPIN (-6000 1975) $PN N49
J 2
(-6010 1985);
DISPLAY 0.489362 (-6010 1985);
PAINT MONO (-6010 1985);
FORCEPROP 0 LASTPIN (-6000 1875) $PN R49
J 2
(-6010 1885);
DISPLAY 0.489362 (-6010 1885);
PAINT MONO (-6010 1885);
FORCEPROP 0 LASTPIN (-6000 1775) $PN U49
J 2
(-6010 1785);
DISPLAY 0.489362 (-6010 1785);
PAINT MONO (-6010 1785);
FORCEPROP 0 LASTPIN (-6000 1675) $PN W52
J 2
(-6010 1685);
DISPLAY 0.489362 (-6010 1685);
PAINT MONO (-6010 1685);
FORCEPROP 0 LASTPIN (-6000 1575) $PN R52
J 2
(-6010 1585);
DISPLAY 0.489362 (-6010 1585);
PAINT MONO (-6010 1585);
FORCEPROP 0 LASTPIN (-6000 1475) $PN U52
J 2
(-6010 1485);
DISPLAY 0.489362 (-6010 1485);
PAINT MONO (-6010 1485);
FORCEPROP 0 LASTPIN (-6000 3025) $PN V41
J 2
(-6010 3035);
DISPLAY 0.489362 (-6010 3035);
PAINT MONO (-6010 3035);
FORCEPROP 0 LASTPIN (-6000 2925) $PN T41
J 2
(-6010 2935);
DISPLAY 0.489362 (-6010 2935);
PAINT MONO (-6010 2935);
FORCEPROP 0 LASTPIN (-6000 2825) $PN P41
J 2
(-6010 2835);
DISPLAY 0.489362 (-6010 2835);
PAINT MONO (-6010 2835);
FORCEPROP 0 LASTPIN (-6000 2725) $PN U44
J 2
(-6010 2735);
DISPLAY 0.489362 (-6010 2735);
PAINT MONO (-6010 2735);
FORCEPROP 0 LASTPIN (-6000 2625) $PN N44
J 2
(-6010 2635);
DISPLAY 0.489362 (-6010 2635);
PAINT MONO (-6010 2635);
FORCEPROP 0 LASTPIN (-6000 2525) $PN R44
J 2
(-6010 2535);
DISPLAY 0.489362 (-6010 2535);
PAINT MONO (-6010 2535);
FORCEPROP 0 LASTPIN (-6000 2425) $PN U47
J 2
(-6010 2435);
DISPLAY 0.489362 (-6010 2435);
PAINT MONO (-6010 2435);
FORCEPROP 0 LASTPIN (-6000 2325) $PN N47
J 2
(-6010 2335);
DISPLAY 0.489362 (-6010 2335);
PAINT MONO (-6010 2335);
FORCEPROP 0 LASTPIN (-6000 2225) $PN R47
J 2
(-6010 2235);
DISPLAY 0.489362 (-6010 2235);
PAINT MONO (-6010 2235);
FORCEPROP 0 LASTPIN (-6000 2125) $PN W50
J 2
(-6010 2135);
DISPLAY 0.489362 (-6010 2135);
PAINT MONO (-6010 2135);
FORCEPROP 0 LASTPIN (-6000 2025) $PN N50
J 2
(-6010 2035);
DISPLAY 0.489362 (-6010 2035);
PAINT MONO (-6010 2035);
FORCEPROP 0 LASTPIN (-6000 1925) $PN R50
J 2
(-6010 1935);
DISPLAY 0.489362 (-6010 1935);
PAINT MONO (-6010 1935);
FORCEPROP 0 LASTPIN (-6000 1825) $PN U50
J 2
(-6010 1835);
DISPLAY 0.489362 (-6010 1835);
PAINT MONO (-6010 1835);
FORCEPROP 0 LASTPIN (-6000 1725) $PN W53
J 2
(-6010 1735);
DISPLAY 0.489362 (-6010 1735);
PAINT MONO (-6010 1735);
FORCEPROP 0 LASTPIN (-6000 1625) $PN R53
J 2
(-6010 1635);
DISPLAY 0.489362 (-6010 1635);
PAINT MONO (-6010 1635);
FORCEPROP 0 LASTPIN (-6000 1525) $PN U53
J 2
(-6010 1535);
DISPLAY 0.489362 (-6010 1535);
PAINT MONO (-6010 1535);
FORCEPROP 0 LASTPIN (-3500 2975) $PN AP41
J 0
(-3490 2985);
DISPLAY 0.489362 (-3490 2985);
PAINT MONO (-3490 2985);
FORCEPROP 0 LASTPIN (-3500 2875) $PN AM41
J 0
(-3490 2885);
DISPLAY 0.489362 (-3490 2885);
PAINT MONO (-3490 2885);
FORCEPROP 0 LASTPIN (-3500 2775) $PN AH41
J 0
(-3490 2785);
DISPLAY 0.489362 (-3490 2785);
PAINT MONO (-3490 2785);
FORCEPROP 0 LASTPIN (-3500 2675) $PN AK41
J 0
(-3490 2685);
DISPLAY 0.489362 (-3490 2685);
PAINT MONO (-3490 2685);
FORCEPROP 0 LASTPIN (-3500 2575) $PN AN44
J 0
(-3490 2585);
DISPLAY 0.489362 (-3490 2585);
PAINT MONO (-3490 2585);
FORCEPROP 0 LASTPIN (-3500 2475) $PN AJ44
J 0
(-3490 2485);
DISPLAY 0.489362 (-3490 2485);
PAINT MONO (-3490 2485);
FORCEPROP 0 LASTPIN (-3500 2375) $PN AL44
J 0
(-3490 2385);
DISPLAY 0.489362 (-3490 2385);
PAINT MONO (-3490 2385);
FORCEPROP 0 LASTPIN (-3500 2275) $PN AN47
J 0
(-3490 2285);
DISPLAY 0.489362 (-3490 2285);
PAINT MONO (-3490 2285);
FORCEPROP 0 LASTPIN (-3500 2175) $PN AJ47
J 0
(-3490 2185);
DISPLAY 0.489362 (-3490 2185);
PAINT MONO (-3490 2185);
FORCEPROP 0 LASTPIN (-3500 2075) $PN AL47
J 0
(-3490 2085);
DISPLAY 0.489362 (-3490 2085);
PAINT MONO (-3490 2085);
FORCEPROP 0 LASTPIN (-3500 1975) $PN AN50
J 0
(-3490 1985);
DISPLAY 0.489362 (-3490 1985);
PAINT MONO (-3490 1985);
FORCEPROP 0 LASTPIN (-3500 1875) $PN AJ50
J 0
(-3490 1885);
DISPLAY 0.489362 (-3490 1885);
PAINT MONO (-3490 1885);
FORCEPROP 0 LASTPIN (-3500 1775) $PN AL50
J 0
(-3490 1785);
DISPLAY 0.489362 (-3490 1785);
PAINT MONO (-3490 1785);
FORCEPROP 0 LASTPIN (-3500 1675) $PN AN53
J 0
(-3490 1685);
DISPLAY 0.489362 (-3490 1685);
PAINT MONO (-3490 1685);
FORCEPROP 0 LASTPIN (-3500 1575) $PN AJ53
J 0
(-3490 1585);
DISPLAY 0.489362 (-3490 1585);
PAINT MONO (-3490 1585);
FORCEPROP 0 LASTPIN (-3500 1475) $PN AL53
J 0
(-3490 1485);
DISPLAY 0.489362 (-3490 1485);
PAINT MONO (-3490 1485);
FORCEPROP 0 LASTPIN (-3500 3025) $PN AP40
J 0
(-3490 3035);
DISPLAY 0.489362 (-3490 3035);
PAINT MONO (-3490 3035);
FORCEPROP 0 LASTPIN (-3500 2925) $PN AM40
J 0
(-3490 2935);
DISPLAY 0.489362 (-3490 2935);
PAINT MONO (-3490 2935);
FORCEPROP 0 LASTPIN (-3500 2825) $PN AH40
J 0
(-3490 2835);
DISPLAY 0.489362 (-3490 2835);
PAINT MONO (-3490 2835);
FORCEPROP 0 LASTPIN (-3500 2725) $PN AK40
J 0
(-3490 2735);
DISPLAY 0.489362 (-3490 2735);
PAINT MONO (-3490 2735);
FORCEPROP 0 LASTPIN (-3500 2625) $PN AN43
J 0
(-3490 2635);
DISPLAY 0.489362 (-3490 2635);
PAINT MONO (-3490 2635);
FORCEPROP 0 LASTPIN (-3500 2525) $PN AJ43
J 0
(-3490 2535);
DISPLAY 0.489362 (-3490 2535);
PAINT MONO (-3490 2535);
FORCEPROP 0 LASTPIN (-3500 2425) $PN AL43
J 0
(-3490 2435);
DISPLAY 0.489362 (-3490 2435);
PAINT MONO (-3490 2435);
FORCEPROP 0 LASTPIN (-3500 2325) $PN AN46
J 0
(-3490 2335);
DISPLAY 0.489362 (-3490 2335);
PAINT MONO (-3490 2335);
FORCEPROP 0 LASTPIN (-3500 2225) $PN AJ46
J 0
(-3490 2235);
DISPLAY 0.489362 (-3490 2235);
PAINT MONO (-3490 2235);
FORCEPROP 0 LASTPIN (-3500 2125) $PN AL46
J 0
(-3490 2135);
DISPLAY 0.489362 (-3490 2135);
PAINT MONO (-3490 2135);
FORCEPROP 0 LASTPIN (-3500 2025) $PN AN49
J 0
(-3490 2035);
DISPLAY 0.489362 (-3490 2035);
PAINT MONO (-3490 2035);
FORCEPROP 0 LASTPIN (-3500 1925) $PN AJ49
J 0
(-3490 1935);
DISPLAY 0.489362 (-3490 1935);
PAINT MONO (-3490 1935);
FORCEPROP 0 LASTPIN (-3500 1825) $PN AL49
J 0
(-3490 1835);
DISPLAY 0.489362 (-3490 1835);
PAINT MONO (-3490 1835);
FORCEPROP 0 LASTPIN (-3500 1725) $PN AN52
J 0
(-3490 1735);
DISPLAY 0.489362 (-3490 1735);
PAINT MONO (-3490 1735);
FORCEPROP 0 LASTPIN (-3500 1625) $PN AJ52
J 0
(-3490 1635);
DISPLAY 0.489362 (-3490 1635);
PAINT MONO (-3490 1635);
FORCEPROP 0 LASTPIN (-3500 1525) $PN AL52
J 0
(-3490 1535);
DISPLAY 0.489362 (-3490 1535);
PAINT MONO (-3490 1535);
FORCEPROP 2 LAST PART_TYPE SMLF
J 0
(-5850 3428);
DISPLAY 1.021277 (-5850 3428);
FORCEPROP 1 LAST MATERIAL IO
J 0
(-5845 3257);
DISPLAY 0.489362 (-5845 3257);
PAINT SKYBLUE (-5845 3257);
FORCEPROP 2 LAST VALUE SOCKET6096_13568-001
J 0
(-5850 3328);
DISPLAY 0.489362 (-5850 3328);
PAINT SKYBLUE (-5850 3328);
FORCEPROP 1 LAST PART_NUMBER DGA^6000030
J 0
(-5845 3384);
DISPLAY 0.489362 (-5845 3384);
PAINT SKYBLUE (-5845 3384);
FORCEPROP 2 LAST CDS_LIB pure_quanta
J 0
(-4750 2275);
DISPLAY INVISIBLE (-4750 2275);
FORCEPROP 1 LAST NEEDS_NO_SIZE TRUE
J 0
(-4750 2275);
DISPLAY 0.723404 (-4750 2275);
PAINT GREEN (-4750 2275);
DISPLAY INVISIBLE (-4750 2275);
FORCEPROP 1 LAST CDS_LMAN_SYM_OUTLINE -1100,950,1100,-950
J 0
(-4750 2275);
DISPLAY 0.468085 (-4750 2275);
PAINT GREEN (-4750 2275);
DISPLAY INVISIBLE (-4750 2275);
FORCEPROP 1 LAST PATH I214
J 0
(-4750 2275);
DISPLAY 0.723404 (-4750 2275);
PAINT GREEN (-4750 2275);
DISPLAY INVISIBLE (-4750 2275);
FORCEADD OFFPAGE..2
(-1825 5975);
FORCEPROP 2 LAST $XR0 23 
J 0
(-1636 5975);
DISPLAY 0.638298 (-1636 5975);
PAINT MONO (-1636 5975);
FORCEPROP 2 LAST CDS_LIB standard
J 0
(-1825 5975);
DISPLAY INVISIBLE (-1825 5975);
FORCEPROP 1 LAST OFFPAGE TRUE
J 0
(-1500 5850);
DISPLAY 0.872340 (-1500 5850);
PAINT GREEN (-1500 5850);
DISPLAY INVISIBLE (-1500 5850);
FORCEPROP 1 LAST COMMENT_BODY TRUE
J 0
(-1870 5880);
DISPLAY 0.872340 (-1870 5880);
PAINT GREEN (-1870 5880);
DISPLAY INVISIBLE (-1870 5880);
FORCEPROP 2 LAST PATH I232
J 0
(-1625 6025);
DISPLAY 1.021277 (-1625 6025);
DISPLAY INVISIBLE (-1625 6025);
FORCEADD TAP..6
R 2
(-3100 5650);
FORCEPROP 3 LASTPIN (-3150 5650) SIG_NAME GMI_CPU1_G0_CPU0_G2_TX_DP<14>
J 0
(-3140 5660);
DISPLAY 0.659574 (-3140 5660);
PAINT MONO (-3140 5660);
DISPLAY INVISIBLE (-3140 5660);
FORCEPROP 1 LASTPIN (-3150 5650) BN 14
J 2
(-3098 5658);
DISPLAY 0.489362 (-3098 5658);
PAINT MONO (-3098 5658);
FORCEPROP 2 LAST BOM_COST IO_SLOT
J 0
(-3600 5750);
DISPLAY 0.829787 (-3600 5750);
DISPLAY INVISIBLE (-3600 5750);
FORCEPROP 2 LAST CDS_LIB mstr_standard
J 0
(-3100 5650);
DISPLAY INVISIBLE (-3100 5650);
FORCEPROP 1 LAST BODY_TYPE PLUMBING
J 2
(-3100 5600);
DISPLAY 0.702128 (-3100 5600);
PAINT GREEN (-3100 5600);
DISPLAY INVISIBLE (-3100 5600);
FORCEPROP 1 LAST HDL_TAP TRUE
J 2
(-3425 5525);
DISPLAY 0.702128 (-3425 5525);
PAINT GREEN (-3425 5525);
DISPLAY INVISIBLE (-3425 5525);
FORCEPROP 1 LAST PATH I235
J 2
(-3098 5650);
DISPLAY 0.872340 (-3098 5650);
PAINT GREEN (-3098 5650);
DISPLAY INVISIBLE (-3098 5650);
FORCEPROP 2 LAST ROOM RISER1
J 0
(-3600 5700);
DISPLAY 0.829787 (-3600 5700);
PAINT RED (-3600 5700);
DISPLAY INVISIBLE (-3600 5700);
FORCEADD TAP..6
R 2
(-3100 5750);
FORCEPROP 3 LASTPIN (-3150 5750) SIG_NAME GMI_CPU1_G0_CPU0_G2_TX_DP<15>
J 0
(-3140 5760);
DISPLAY 0.659574 (-3140 5760);
PAINT MONO (-3140 5760);
DISPLAY INVISIBLE (-3140 5760);
FORCEPROP 1 LASTPIN (-3150 5750) BN 15
J 2
(-3098 5758);
DISPLAY 0.489362 (-3098 5758);
PAINT MONO (-3098 5758);
FORCEPROP 2 LAST BOM_COST IO_SLOT
J 0
(-3600 5850);
DISPLAY 0.829787 (-3600 5850);
DISPLAY INVISIBLE (-3600 5850);
FORCEPROP 2 LAST CDS_LIB mstr_standard
J 0
(-3100 5750);
DISPLAY INVISIBLE (-3100 5750);
FORCEPROP 1 LAST BODY_TYPE PLUMBING
J 2
(-3100 5700);
DISPLAY 0.702128 (-3100 5700);
PAINT GREEN (-3100 5700);
DISPLAY INVISIBLE (-3100 5700);
FORCEPROP 1 LAST HDL_TAP TRUE
J 2
(-3425 5625);
DISPLAY 0.702128 (-3425 5625);
PAINT GREEN (-3425 5625);
DISPLAY INVISIBLE (-3425 5625);
FORCEPROP 1 LAST PATH I236
J 2
(-3098 5750);
DISPLAY 0.872340 (-3098 5750);
PAINT GREEN (-3098 5750);
DISPLAY INVISIBLE (-3098 5750);
FORCEPROP 2 LAST ROOM RISER1
J 0
(-3600 5800);
DISPLAY 0.829787 (-3600 5800);
PAINT RED (-3600 5800);
DISPLAY INVISIBLE (-3600 5800);
FORCEADD TAP..6
R 2
(-3100 5550);
FORCEPROP 3 LASTPIN (-3150 5550) SIG_NAME GMI_CPU1_G0_CPU0_G2_TX_DP<13>
J 0
(-3140 5560);
DISPLAY 0.659574 (-3140 5560);
PAINT MONO (-3140 5560);
DISPLAY INVISIBLE (-3140 5560);
FORCEPROP 1 LASTPIN (-3150 5550) BN 13
J 2
(-3098 5558);
DISPLAY 0.489362 (-3098 5558);
PAINT MONO (-3098 5558);
FORCEPROP 2 LAST BOM_COST IO_SLOT
J 0
(-3600 5650);
DISPLAY 0.829787 (-3600 5650);
DISPLAY INVISIBLE (-3600 5650);
FORCEPROP 2 LAST CDS_LIB standard
J 0
(-3100 5550);
DISPLAY INVISIBLE (-3100 5550);
FORCEPROP 1 LAST BODY_TYPE PLUMBING
J 2
(-3100 5500);
DISPLAY 0.702128 (-3100 5500);
PAINT GREEN (-3100 5500);
DISPLAY INVISIBLE (-3100 5500);
FORCEPROP 1 LAST HDL_TAP TRUE
J 2
(-3425 5425);
DISPLAY 0.702128 (-3425 5425);
PAINT GREEN (-3425 5425);
DISPLAY INVISIBLE (-3425 5425);
FORCEPROP 1 LAST PATH I240
J 2
(-3098 5550);
DISPLAY 0.872340 (-3098 5550);
PAINT GREEN (-3098 5550);
DISPLAY INVISIBLE (-3098 5550);
FORCEPROP 2 LAST ROOM RISER1
J 0
(-3600 5600);
DISPLAY 0.829787 (-3600 5600);
PAINT RED (-3600 5600);
DISPLAY INVISIBLE (-3600 5600);
FORCEADD TAP..6
R 2
(-3100 5450);
FORCEPROP 3 LASTPIN (-3150 5450) SIG_NAME GMI_CPU1_G0_CPU0_G2_TX_DP<12>
J 0
(-3140 5460);
DISPLAY 0.659574 (-3140 5460);
PAINT MONO (-3140 5460);
DISPLAY INVISIBLE (-3140 5460);
FORCEPROP 1 LASTPIN (-3150 5450) BN 12
J 2
(-3098 5458);
DISPLAY 0.489362 (-3098 5458);
PAINT MONO (-3098 5458);
FORCEPROP 2 LAST BOM_COST IO_SLOT
J 0
(-3600 5550);
DISPLAY 0.829787 (-3600 5550);
DISPLAY INVISIBLE (-3600 5550);
FORCEPROP 2 LAST CDS_LIB standard
J 0
(-3100 5450);
DISPLAY INVISIBLE (-3100 5450);
FORCEPROP 1 LAST BODY_TYPE PLUMBING
J 2
(-3100 5400);
DISPLAY 0.702128 (-3100 5400);
PAINT GREEN (-3100 5400);
DISPLAY INVISIBLE (-3100 5400);
FORCEPROP 1 LAST HDL_TAP TRUE
J 2
(-3425 5325);
DISPLAY 0.702128 (-3425 5325);
PAINT GREEN (-3425 5325);
DISPLAY INVISIBLE (-3425 5325);
FORCEPROP 1 LAST PATH I241
J 2
(-3098 5450);
DISPLAY 0.872340 (-3098 5450);
PAINT GREEN (-3098 5450);
DISPLAY INVISIBLE (-3098 5450);
FORCEPROP 2 LAST ROOM RISER1
J 0
(-3600 5500);
DISPLAY 0.829787 (-3600 5500);
PAINT RED (-3600 5500);
DISPLAY INVISIBLE (-3600 5500);
FORCEADD TAP..6
R 2
(-3100 5350);
FORCEPROP 3 LASTPIN (-3150 5350) SIG_NAME GMI_CPU1_G0_CPU0_G2_TX_DP<11>
J 0
(-3140 5360);
DISPLAY 0.659574 (-3140 5360);
PAINT MONO (-3140 5360);
DISPLAY INVISIBLE (-3140 5360);
FORCEPROP 1 LASTPIN (-3150 5350) BN 11
J 2
(-3098 5358);
DISPLAY 0.489362 (-3098 5358);
PAINT MONO (-3098 5358);
FORCEPROP 2 LAST BOM_COST IO_SLOT
J 0
(-3600 5450);
DISPLAY 0.829787 (-3600 5450);
DISPLAY INVISIBLE (-3600 5450);
FORCEPROP 2 LAST CDS_LIB standard
J 0
(-3100 5350);
DISPLAY INVISIBLE (-3100 5350);
FORCEPROP 1 LAST BODY_TYPE PLUMBING
J 2
(-3100 5300);
DISPLAY 0.702128 (-3100 5300);
PAINT GREEN (-3100 5300);
DISPLAY INVISIBLE (-3100 5300);
FORCEPROP 1 LAST HDL_TAP TRUE
J 2
(-3425 5225);
DISPLAY 0.702128 (-3425 5225);
PAINT GREEN (-3425 5225);
DISPLAY INVISIBLE (-3425 5225);
FORCEPROP 1 LAST PATH I244
J 2
(-3098 5350);
DISPLAY 0.872340 (-3098 5350);
PAINT GREEN (-3098 5350);
DISPLAY INVISIBLE (-3098 5350);
FORCEPROP 2 LAST ROOM RISER1
J 0
(-3600 5400);
DISPLAY 0.829787 (-3600 5400);
PAINT RED (-3600 5400);
DISPLAY INVISIBLE (-3600 5400);
FORCEADD TAP..6
R 2
(-3100 5250);
FORCEPROP 3 LASTPIN (-3150 5250) SIG_NAME GMI_CPU1_G0_CPU0_G2_TX_DP<10>
J 0
(-3140 5260);
DISPLAY 0.659574 (-3140 5260);
PAINT MONO (-3140 5260);
DISPLAY INVISIBLE (-3140 5260);
FORCEPROP 1 LASTPIN (-3150 5250) BN 10
J 2
(-3098 5258);
DISPLAY 0.489362 (-3098 5258);
PAINT MONO (-3098 5258);
FORCEPROP 2 LAST BOM_COST IO_SLOT
J 0
(-3600 5350);
DISPLAY 0.829787 (-3600 5350);
DISPLAY INVISIBLE (-3600 5350);
FORCEPROP 2 LAST CDS_LIB standard
J 0
(-3100 5250);
DISPLAY INVISIBLE (-3100 5250);
FORCEPROP 1 LAST BODY_TYPE PLUMBING
J 2
(-3100 5200);
DISPLAY 0.702128 (-3100 5200);
PAINT GREEN (-3100 5200);
DISPLAY INVISIBLE (-3100 5200);
FORCEPROP 1 LAST HDL_TAP TRUE
J 2
(-3425 5125);
DISPLAY 0.702128 (-3425 5125);
PAINT GREEN (-3425 5125);
DISPLAY INVISIBLE (-3425 5125);
FORCEPROP 1 LAST PATH I245
J 2
(-3098 5250);
DISPLAY 0.872340 (-3098 5250);
PAINT GREEN (-3098 5250);
DISPLAY INVISIBLE (-3098 5250);
FORCEPROP 2 LAST ROOM RISER1
J 0
(-3600 5300);
DISPLAY 0.829787 (-3600 5300);
PAINT RED (-3600 5300);
DISPLAY INVISIBLE (-3600 5300);
FORCEADD TAP..6
R 2
(-3100 5150);
FORCEPROP 3 LASTPIN (-3150 5150) SIG_NAME GMI_CPU1_G0_CPU0_G2_TX_DP<9>
J 0
(-3140 5160);
DISPLAY 0.659574 (-3140 5160);
PAINT MONO (-3140 5160);
DISPLAY INVISIBLE (-3140 5160);
FORCEPROP 1 LASTPIN (-3150 5150) BN 9
J 2
(-3098 5158);
DISPLAY 0.489362 (-3098 5158);
PAINT MONO (-3098 5158);
FORCEPROP 2 LAST BOM_COST IO_SLOT
J 0
(-3600 5250);
DISPLAY 0.829787 (-3600 5250);
DISPLAY INVISIBLE (-3600 5250);
FORCEPROP 2 LAST CDS_LIB standard
J 0
(-3100 5150);
DISPLAY INVISIBLE (-3100 5150);
FORCEPROP 1 LAST BODY_TYPE PLUMBING
J 2
(-3100 5100);
DISPLAY 0.702128 (-3100 5100);
PAINT GREEN (-3100 5100);
DISPLAY INVISIBLE (-3100 5100);
FORCEPROP 1 LAST HDL_TAP TRUE
J 2
(-3425 5025);
DISPLAY 0.702128 (-3425 5025);
PAINT GREEN (-3425 5025);
DISPLAY INVISIBLE (-3425 5025);
FORCEPROP 1 LAST PATH I246
J 2
(-3098 5150);
DISPLAY 0.872340 (-3098 5150);
PAINT GREEN (-3098 5150);
DISPLAY INVISIBLE (-3098 5150);
FORCEPROP 2 LAST ROOM RISER1
J 0
(-3600 5200);
DISPLAY 0.829787 (-3600 5200);
PAINT RED (-3600 5200);
DISPLAY INVISIBLE (-3600 5200);
FORCEADD TAP..6
R 2
(-3100 5050);
FORCEPROP 3 LASTPIN (-3150 5050) SIG_NAME GMI_CPU1_G0_CPU0_G2_TX_DP<8>
J 0
(-3140 5060);
DISPLAY 0.659574 (-3140 5060);
PAINT MONO (-3140 5060);
DISPLAY INVISIBLE (-3140 5060);
FORCEPROP 1 LASTPIN (-3150 5050) BN 8
J 2
(-3098 5058);
DISPLAY 0.489362 (-3098 5058);
PAINT MONO (-3098 5058);
FORCEPROP 2 LAST BOM_COST IO_SLOT
J 0
(-3600 5150);
DISPLAY 0.829787 (-3600 5150);
DISPLAY INVISIBLE (-3600 5150);
FORCEPROP 2 LAST CDS_LIB standard
J 0
(-3100 5050);
DISPLAY INVISIBLE (-3100 5050);
FORCEPROP 1 LAST BODY_TYPE PLUMBING
J 2
(-3100 5000);
DISPLAY 0.702128 (-3100 5000);
PAINT GREEN (-3100 5000);
DISPLAY INVISIBLE (-3100 5000);
FORCEPROP 1 LAST HDL_TAP TRUE
J 2
(-3425 4925);
DISPLAY 0.702128 (-3425 4925);
PAINT GREEN (-3425 4925);
DISPLAY INVISIBLE (-3425 4925);
FORCEPROP 1 LAST PATH I250
J 2
(-3098 5050);
DISPLAY 0.872340 (-3098 5050);
PAINT GREEN (-3098 5050);
DISPLAY INVISIBLE (-3098 5050);
FORCEPROP 2 LAST ROOM RISER1
J 0
(-3600 5100);
DISPLAY 0.829787 (-3600 5100);
PAINT RED (-3600 5100);
DISPLAY INVISIBLE (-3600 5100);
FORCEADD TAP..6
R 2
(-3100 4950);
FORCEPROP 3 LASTPIN (-3150 4950) SIG_NAME GMI_CPU1_G0_CPU0_G2_TX_DP<7>
J 0
(-3140 4960);
DISPLAY 0.659574 (-3140 4960);
PAINT MONO (-3140 4960);
DISPLAY INVISIBLE (-3140 4960);
FORCEPROP 1 LASTPIN (-3150 4950) BN 7
J 2
(-3098 4958);
DISPLAY 0.489362 (-3098 4958);
PAINT MONO (-3098 4958);
FORCEPROP 2 LAST BOM_COST IO_SLOT
J 0
(-3600 5050);
DISPLAY 0.829787 (-3600 5050);
DISPLAY INVISIBLE (-3600 5050);
FORCEPROP 2 LAST CDS_LIB standard
J 0
(-3100 4950);
DISPLAY INVISIBLE (-3100 4950);
FORCEPROP 1 LAST BODY_TYPE PLUMBING
J 2
(-3100 4900);
DISPLAY 0.702128 (-3100 4900);
PAINT GREEN (-3100 4900);
DISPLAY INVISIBLE (-3100 4900);
FORCEPROP 1 LAST HDL_TAP TRUE
J 2
(-3425 4825);
DISPLAY 0.702128 (-3425 4825);
PAINT GREEN (-3425 4825);
DISPLAY INVISIBLE (-3425 4825);
FORCEPROP 1 LAST PATH I251
J 2
(-3098 4950);
DISPLAY 0.872340 (-3098 4950);
PAINT GREEN (-3098 4950);
DISPLAY INVISIBLE (-3098 4950);
FORCEPROP 2 LAST ROOM RISER1
J 0
(-3600 5000);
DISPLAY 0.829787 (-3600 5000);
PAINT RED (-3600 5000);
DISPLAY INVISIBLE (-3600 5000);
FORCEADD TAP..6
R 2
(-3100 4850);
FORCEPROP 3 LASTPIN (-3150 4850) SIG_NAME GMI_CPU1_G0_CPU0_G2_TX_DP<6>
J 0
(-3140 4860);
DISPLAY 0.659574 (-3140 4860);
PAINT MONO (-3140 4860);
DISPLAY INVISIBLE (-3140 4860);
FORCEPROP 1 LASTPIN (-3150 4850) BN 6
J 2
(-3098 4858);
DISPLAY 0.489362 (-3098 4858);
PAINT MONO (-3098 4858);
FORCEPROP 2 LAST BOM_COST IO_SLOT
J 0
(-3600 4950);
DISPLAY 0.829787 (-3600 4950);
DISPLAY INVISIBLE (-3600 4950);
FORCEPROP 2 LAST CDS_LIB standard
J 0
(-3100 4850);
DISPLAY INVISIBLE (-3100 4850);
FORCEPROP 1 LAST BODY_TYPE PLUMBING
J 2
(-3100 4800);
DISPLAY 0.702128 (-3100 4800);
PAINT GREEN (-3100 4800);
DISPLAY INVISIBLE (-3100 4800);
FORCEPROP 1 LAST HDL_TAP TRUE
J 2
(-3425 4725);
DISPLAY 0.702128 (-3425 4725);
PAINT GREEN (-3425 4725);
DISPLAY INVISIBLE (-3425 4725);
FORCEPROP 1 LAST PATH I254
J 2
(-3098 4850);
DISPLAY 0.872340 (-3098 4850);
PAINT GREEN (-3098 4850);
DISPLAY INVISIBLE (-3098 4850);
FORCEPROP 2 LAST ROOM RISER1
J 0
(-3600 4900);
DISPLAY 0.829787 (-3600 4900);
PAINT RED (-3600 4900);
DISPLAY INVISIBLE (-3600 4900);
FORCEADD TAP..6
R 2
(-3100 4750);
FORCEPROP 3 LASTPIN (-3150 4750) SIG_NAME GMI_CPU1_G0_CPU0_G2_TX_DP<5>
J 0
(-3140 4760);
DISPLAY 0.659574 (-3140 4760);
PAINT MONO (-3140 4760);
DISPLAY INVISIBLE (-3140 4760);
FORCEPROP 1 LASTPIN (-3150 4750) BN 5
J 2
(-3098 4758);
DISPLAY 0.489362 (-3098 4758);
PAINT MONO (-3098 4758);
FORCEPROP 2 LAST BOM_COST IO_SLOT
J 0
(-3600 4850);
DISPLAY 0.829787 (-3600 4850);
DISPLAY INVISIBLE (-3600 4850);
FORCEPROP 2 LAST CDS_LIB standard
J 0
(-3100 4750);
DISPLAY INVISIBLE (-3100 4750);
FORCEPROP 1 LAST BODY_TYPE PLUMBING
J 2
(-3100 4700);
DISPLAY 0.702128 (-3100 4700);
PAINT GREEN (-3100 4700);
DISPLAY INVISIBLE (-3100 4700);
FORCEPROP 1 LAST HDL_TAP TRUE
J 2
(-3425 4625);
DISPLAY 0.702128 (-3425 4625);
PAINT GREEN (-3425 4625);
DISPLAY INVISIBLE (-3425 4625);
FORCEPROP 1 LAST PATH I255
J 2
(-3098 4750);
DISPLAY 0.872340 (-3098 4750);
PAINT GREEN (-3098 4750);
DISPLAY INVISIBLE (-3098 4750);
FORCEPROP 2 LAST ROOM RISER1
J 0
(-3600 4800);
DISPLAY 0.829787 (-3600 4800);
PAINT RED (-3600 4800);
DISPLAY INVISIBLE (-3600 4800);
FORCEADD TAP..6
R 2
(-3100 4650);
FORCEPROP 3 LASTPIN (-3150 4650) SIG_NAME GMI_CPU1_G0_CPU0_G2_TX_DP<4>
J 0
(-3140 4660);
DISPLAY 0.659574 (-3140 4660);
PAINT MONO (-3140 4660);
DISPLAY INVISIBLE (-3140 4660);
FORCEPROP 1 LASTPIN (-3150 4650) BN 4
J 2
(-3098 4658);
DISPLAY 0.489362 (-3098 4658);
PAINT MONO (-3098 4658);
FORCEPROP 2 LAST BOM_COST IO_SLOT
J 0
(-3600 4750);
DISPLAY 0.829787 (-3600 4750);
DISPLAY INVISIBLE (-3600 4750);
FORCEPROP 2 LAST CDS_LIB standard
J 0
(-3100 4650);
DISPLAY INVISIBLE (-3100 4650);
FORCEPROP 1 LAST BODY_TYPE PLUMBING
J 2
(-3100 4600);
DISPLAY 0.702128 (-3100 4600);
PAINT GREEN (-3100 4600);
DISPLAY INVISIBLE (-3100 4600);
FORCEPROP 1 LAST HDL_TAP TRUE
J 2
(-3425 4525);
DISPLAY 0.702128 (-3425 4525);
PAINT GREEN (-3425 4525);
DISPLAY INVISIBLE (-3425 4525);
FORCEPROP 1 LAST PATH I256
J 2
(-3098 4650);
DISPLAY 0.872340 (-3098 4650);
PAINT GREEN (-3098 4650);
DISPLAY INVISIBLE (-3098 4650);
FORCEPROP 2 LAST ROOM RISER1
J 0
(-3600 4700);
DISPLAY 0.829787 (-3600 4700);
PAINT RED (-3600 4700);
DISPLAY INVISIBLE (-3600 4700);
FORCEADD TAP..6
R 2
(-3100 4550);
FORCEPROP 3 LASTPIN (-3150 4550) SIG_NAME GMI_CPU1_G0_CPU0_G2_TX_DP<3>
J 0
(-3140 4560);
DISPLAY 0.659574 (-3140 4560);
PAINT MONO (-3140 4560);
DISPLAY INVISIBLE (-3140 4560);
FORCEPROP 1 LASTPIN (-3150 4550) BN 3
J 2
(-3098 4558);
DISPLAY 0.489362 (-3098 4558);
PAINT MONO (-3098 4558);
FORCEPROP 2 LAST BOM_COST IO_SLOT
J 0
(-3600 4650);
DISPLAY 0.829787 (-3600 4650);
DISPLAY INVISIBLE (-3600 4650);
FORCEPROP 2 LAST CDS_LIB standard
J 0
(-3100 4550);
DISPLAY INVISIBLE (-3100 4550);
FORCEPROP 1 LAST BODY_TYPE PLUMBING
J 2
(-3100 4500);
DISPLAY 0.702128 (-3100 4500);
PAINT GREEN (-3100 4500);
DISPLAY INVISIBLE (-3100 4500);
FORCEPROP 1 LAST HDL_TAP TRUE
J 2
(-3425 4425);
DISPLAY 0.702128 (-3425 4425);
PAINT GREEN (-3425 4425);
DISPLAY INVISIBLE (-3425 4425);
FORCEPROP 1 LAST PATH I260
J 2
(-3098 4550);
DISPLAY 0.872340 (-3098 4550);
PAINT GREEN (-3098 4550);
DISPLAY INVISIBLE (-3098 4550);
FORCEPROP 2 LAST ROOM RISER1
J 0
(-3600 4600);
DISPLAY 0.829787 (-3600 4600);
PAINT RED (-3600 4600);
DISPLAY INVISIBLE (-3600 4600);
FORCEADD TAP..6
R 2
(-3100 4450);
FORCEPROP 3 LASTPIN (-3150 4450) SIG_NAME GMI_CPU1_G0_CPU0_G2_TX_DP<2>
J 0
(-3140 4460);
DISPLAY 0.659574 (-3140 4460);
PAINT MONO (-3140 4460);
DISPLAY INVISIBLE (-3140 4460);
FORCEPROP 1 LASTPIN (-3150 4450) BN 2
J 2
(-3098 4458);
DISPLAY 0.489362 (-3098 4458);
PAINT MONO (-3098 4458);
FORCEPROP 2 LAST BOM_COST IO_SLOT
J 0
(-3600 4550);
DISPLAY 0.829787 (-3600 4550);
DISPLAY INVISIBLE (-3600 4550);
FORCEPROP 2 LAST CDS_LIB standard
J 0
(-3100 4450);
DISPLAY INVISIBLE (-3100 4450);
FORCEPROP 1 LAST BODY_TYPE PLUMBING
J 2
(-3100 4400);
DISPLAY 0.702128 (-3100 4400);
PAINT GREEN (-3100 4400);
DISPLAY INVISIBLE (-3100 4400);
FORCEPROP 1 LAST HDL_TAP TRUE
J 2
(-3425 4325);
DISPLAY 0.702128 (-3425 4325);
PAINT GREEN (-3425 4325);
DISPLAY INVISIBLE (-3425 4325);
FORCEPROP 1 LAST PATH I261
J 2
(-3098 4450);
DISPLAY 0.872340 (-3098 4450);
PAINT GREEN (-3098 4450);
DISPLAY INVISIBLE (-3098 4450);
FORCEPROP 2 LAST ROOM RISER1
J 0
(-3600 4500);
DISPLAY 0.829787 (-3600 4500);
PAINT RED (-3600 4500);
DISPLAY INVISIBLE (-3600 4500);
FORCEADD TAP..6
R 2
(-3100 4350);
FORCEPROP 3 LASTPIN (-3150 4350) SIG_NAME GMI_CPU1_G0_CPU0_G2_TX_DP<1>
J 0
(-3140 4360);
DISPLAY 0.659574 (-3140 4360);
PAINT MONO (-3140 4360);
DISPLAY INVISIBLE (-3140 4360);
FORCEPROP 1 LASTPIN (-3150 4350) BN 1
J 2
(-3098 4358);
DISPLAY 0.489362 (-3098 4358);
PAINT MONO (-3098 4358);
FORCEPROP 2 LAST BOM_COST IO_SLOT
J 0
(-3600 4450);
DISPLAY 0.829787 (-3600 4450);
DISPLAY INVISIBLE (-3600 4450);
FORCEPROP 2 LAST CDS_LIB standard
J 0
(-3100 4350);
DISPLAY INVISIBLE (-3100 4350);
FORCEPROP 1 LAST BODY_TYPE PLUMBING
J 2
(-3100 4300);
DISPLAY 0.702128 (-3100 4300);
PAINT GREEN (-3100 4300);
DISPLAY INVISIBLE (-3100 4300);
FORCEPROP 1 LAST HDL_TAP TRUE
J 2
(-3425 4225);
DISPLAY 0.702128 (-3425 4225);
PAINT GREEN (-3425 4225);
DISPLAY INVISIBLE (-3425 4225);
FORCEPROP 1 LAST PATH I264
J 2
(-3098 4350);
DISPLAY 0.872340 (-3098 4350);
PAINT GREEN (-3098 4350);
DISPLAY INVISIBLE (-3098 4350);
FORCEPROP 2 LAST ROOM RISER1
J 0
(-3600 4400);
DISPLAY 0.829787 (-3600 4400);
PAINT RED (-3600 4400);
DISPLAY INVISIBLE (-3600 4400);
FORCEADD TAP..6
R 2
(-3100 4250);
FORCEPROP 3 LASTPIN (-3150 4250) SIG_NAME GMI_CPU1_G0_CPU0_G2_TX_DP<0>
J 0
(-3140 4260);
DISPLAY 0.659574 (-3140 4260);
PAINT MONO (-3140 4260);
DISPLAY INVISIBLE (-3140 4260);
FORCEPROP 1 LASTPIN (-3150 4250) BN 0
J 2
(-3098 4258);
DISPLAY 0.489362 (-3098 4258);
PAINT MONO (-3098 4258);
FORCEPROP 2 LAST BOM_COST IO_SLOT
J 0
(-3600 4350);
DISPLAY 0.829787 (-3600 4350);
DISPLAY INVISIBLE (-3600 4350);
FORCEPROP 2 LAST CDS_LIB standard
J 0
(-3100 4250);
DISPLAY INVISIBLE (-3100 4250);
FORCEPROP 1 LAST BODY_TYPE PLUMBING
J 2
(-3100 4200);
DISPLAY 0.702128 (-3100 4200);
PAINT GREEN (-3100 4200);
DISPLAY INVISIBLE (-3100 4200);
FORCEPROP 1 LAST HDL_TAP TRUE
J 2
(-3425 4125);
DISPLAY 0.702128 (-3425 4125);
PAINT GREEN (-3425 4125);
DISPLAY INVISIBLE (-3425 4125);
FORCEPROP 1 LAST PATH I265
J 2
(-3098 4250);
DISPLAY 0.872340 (-3098 4250);
PAINT GREEN (-3098 4250);
DISPLAY INVISIBLE (-3098 4250);
FORCEPROP 2 LAST ROOM RISER1
J 0
(-3600 4300);
DISPLAY 0.829787 (-3600 4300);
PAINT RED (-3600 4300);
DISPLAY INVISIBLE (-3600 4300);
FORCEADD OFFPAGE..2
(-1800 3250);
FORCEPROP 2 LAST $XR0 23 
J 0
(-1611 3250);
DISPLAY 0.638298 (-1611 3250);
PAINT MONO (-1611 3250);
FORCEPROP 2 LAST CDS_LIB standard
J 0
(-1800 3250);
DISPLAY INVISIBLE (-1800 3250);
FORCEPROP 1 LAST OFFPAGE TRUE
J 0
(-1475 3125);
DISPLAY 0.872340 (-1475 3125);
PAINT GREEN (-1475 3125);
DISPLAY INVISIBLE (-1475 3125);
FORCEPROP 1 LAST COMMENT_BODY TRUE
J 0
(-1845 3155);
DISPLAY 0.872340 (-1845 3155);
PAINT GREEN (-1845 3155);
DISPLAY INVISIBLE (-1845 3155);
FORCEPROP 2 LAST PATH I267
J 0
(-1600 3300);
DISPLAY 1.021277 (-1600 3300);
DISPLAY INVISIBLE (-1600 3300);
FORCEADD TAP..6
R 2
(-3075 2925);
FORCEPROP 3 LASTPIN (-3125 2925) SIG_NAME GMI_CPU1_G1_CPU0_G3_TX_DP<14>
J 0
(-3115 2935);
DISPLAY 0.659574 (-3115 2935);
PAINT MONO (-3115 2935);
DISPLAY INVISIBLE (-3115 2935);
FORCEPROP 1 LASTPIN (-3125 2925) BN 14
J 2
(-3073 2933);
DISPLAY 0.489362 (-3073 2933);
PAINT MONO (-3073 2933);
FORCEPROP 2 LAST CDS_LIB mstr_standard
J 0
(-3075 2925);
DISPLAY INVISIBLE (-3075 2925);
FORCEPROP 2 LAST BOM_COST IO_SLOT
J 0
(-3575 3025);
DISPLAY 0.829787 (-3575 3025);
DISPLAY INVISIBLE (-3575 3025);
FORCEPROP 1 LAST BODY_TYPE PLUMBING
J 2
(-3075 2875);
DISPLAY 0.702128 (-3075 2875);
PAINT GREEN (-3075 2875);
DISPLAY INVISIBLE (-3075 2875);
FORCEPROP 1 LAST HDL_TAP TRUE
J 2
(-3400 2800);
DISPLAY 0.702128 (-3400 2800);
PAINT GREEN (-3400 2800);
DISPLAY INVISIBLE (-3400 2800);
FORCEPROP 1 LAST PATH I270
J 2
(-3073 2925);
DISPLAY 0.872340 (-3073 2925);
PAINT GREEN (-3073 2925);
DISPLAY INVISIBLE (-3073 2925);
FORCEPROP 2 LAST ROOM RISER1
J 0
(-3575 2975);
DISPLAY 0.829787 (-3575 2975);
PAINT RED (-3575 2975);
DISPLAY INVISIBLE (-3575 2975);
FORCEADD TAP..6
R 2
(-3075 2825);
FORCEPROP 3 LASTPIN (-3125 2825) SIG_NAME GMI_CPU1_G1_CPU0_G3_TX_DP<13>
J 0
(-3115 2835);
DISPLAY 0.659574 (-3115 2835);
PAINT MONO (-3115 2835);
DISPLAY INVISIBLE (-3115 2835);
FORCEPROP 1 LASTPIN (-3125 2825) BN 13
J 2
(-3073 2833);
DISPLAY 0.489362 (-3073 2833);
PAINT MONO (-3073 2833);
FORCEPROP 2 LAST CDS_LIB standard
J 0
(-3075 2825);
DISPLAY INVISIBLE (-3075 2825);
FORCEPROP 2 LAST BOM_COST IO_SLOT
J 0
(-3575 2925);
DISPLAY 0.829787 (-3575 2925);
DISPLAY INVISIBLE (-3575 2925);
FORCEPROP 1 LAST BODY_TYPE PLUMBING
J 2
(-3075 2775);
DISPLAY 0.702128 (-3075 2775);
PAINT GREEN (-3075 2775);
DISPLAY INVISIBLE (-3075 2775);
FORCEPROP 1 LAST HDL_TAP TRUE
J 2
(-3400 2700);
DISPLAY 0.702128 (-3400 2700);
PAINT GREEN (-3400 2700);
DISPLAY INVISIBLE (-3400 2700);
FORCEPROP 1 LAST PATH I271
J 2
(-3073 2825);
DISPLAY 0.872340 (-3073 2825);
PAINT GREEN (-3073 2825);
DISPLAY INVISIBLE (-3073 2825);
FORCEPROP 2 LAST ROOM RISER1
J 0
(-3575 2875);
DISPLAY 0.829787 (-3575 2875);
PAINT RED (-3575 2875);
DISPLAY INVISIBLE (-3575 2875);
FORCEADD TAP..6
R 2
(-3075 3025);
FORCEPROP 3 LASTPIN (-3125 3025) SIG_NAME GMI_CPU1_G1_CPU0_G3_TX_DP<15>
J 0
(-3115 3035);
DISPLAY 0.659574 (-3115 3035);
PAINT MONO (-3115 3035);
DISPLAY INVISIBLE (-3115 3035);
FORCEPROP 1 LASTPIN (-3125 3025) BN 15
J 2
(-3073 3033);
DISPLAY 0.489362 (-3073 3033);
PAINT MONO (-3073 3033);
FORCEPROP 2 LAST CDS_LIB mstr_standard
J 0
(-3075 3025);
DISPLAY INVISIBLE (-3075 3025);
FORCEPROP 2 LAST BOM_COST IO_SLOT
J 0
(-3575 3125);
DISPLAY 0.829787 (-3575 3125);
DISPLAY INVISIBLE (-3575 3125);
FORCEPROP 1 LAST BODY_TYPE PLUMBING
J 2
(-3075 2975);
DISPLAY 0.702128 (-3075 2975);
PAINT GREEN (-3075 2975);
DISPLAY INVISIBLE (-3075 2975);
FORCEPROP 1 LAST HDL_TAP TRUE
J 2
(-3400 2900);
DISPLAY 0.702128 (-3400 2900);
PAINT GREEN (-3400 2900);
DISPLAY INVISIBLE (-3400 2900);
FORCEPROP 1 LAST PATH I272
J 2
(-3073 3025);
DISPLAY 0.872340 (-3073 3025);
PAINT GREEN (-3073 3025);
DISPLAY INVISIBLE (-3073 3025);
FORCEPROP 2 LAST ROOM RISER1
J 0
(-3575 3075);
DISPLAY 0.829787 (-3575 3075);
PAINT RED (-3575 3075);
DISPLAY INVISIBLE (-3575 3075);
FORCEADD TAP..6
R 2
(-3075 2725);
FORCEPROP 3 LASTPIN (-3125 2725) SIG_NAME GMI_CPU1_G1_CPU0_G3_TX_DP<12>
J 0
(-3115 2735);
DISPLAY 0.659574 (-3115 2735);
PAINT MONO (-3115 2735);
DISPLAY INVISIBLE (-3115 2735);
FORCEPROP 1 LASTPIN (-3125 2725) BN 12
J 2
(-3073 2733);
DISPLAY 0.489362 (-3073 2733);
PAINT MONO (-3073 2733);
FORCEPROP 2 LAST CDS_LIB standard
J 0
(-3075 2725);
DISPLAY INVISIBLE (-3075 2725);
FORCEPROP 2 LAST BOM_COST IO_SLOT
J 0
(-3575 2825);
DISPLAY 0.829787 (-3575 2825);
DISPLAY INVISIBLE (-3575 2825);
FORCEPROP 1 LAST BODY_TYPE PLUMBING
J 2
(-3075 2675);
DISPLAY 0.702128 (-3075 2675);
PAINT GREEN (-3075 2675);
DISPLAY INVISIBLE (-3075 2675);
FORCEPROP 1 LAST HDL_TAP TRUE
J 2
(-3400 2600);
DISPLAY 0.702128 (-3400 2600);
PAINT GREEN (-3400 2600);
DISPLAY INVISIBLE (-3400 2600);
FORCEPROP 1 LAST PATH I276
J 2
(-3073 2725);
DISPLAY 0.872340 (-3073 2725);
PAINT GREEN (-3073 2725);
DISPLAY INVISIBLE (-3073 2725);
FORCEPROP 2 LAST ROOM RISER1
J 0
(-3575 2775);
DISPLAY 0.829787 (-3575 2775);
PAINT RED (-3575 2775);
DISPLAY INVISIBLE (-3575 2775);
FORCEADD TAP..6
R 2
(-3075 2625);
FORCEPROP 3 LASTPIN (-3125 2625) SIG_NAME GMI_CPU1_G1_CPU0_G3_TX_DP<11>
J 0
(-3115 2635);
DISPLAY 0.659574 (-3115 2635);
PAINT MONO (-3115 2635);
DISPLAY INVISIBLE (-3115 2635);
FORCEPROP 1 LASTPIN (-3125 2625) BN 11
J 2
(-3073 2633);
DISPLAY 0.489362 (-3073 2633);
PAINT MONO (-3073 2633);
FORCEPROP 2 LAST CDS_LIB standard
J 0
(-3075 2625);
DISPLAY INVISIBLE (-3075 2625);
FORCEPROP 2 LAST BOM_COST IO_SLOT
J 0
(-3575 2725);
DISPLAY 0.829787 (-3575 2725);
DISPLAY INVISIBLE (-3575 2725);
FORCEPROP 1 LAST BODY_TYPE PLUMBING
J 2
(-3075 2575);
DISPLAY 0.702128 (-3075 2575);
PAINT GREEN (-3075 2575);
DISPLAY INVISIBLE (-3075 2575);
FORCEPROP 1 LAST HDL_TAP TRUE
J 2
(-3400 2500);
DISPLAY 0.702128 (-3400 2500);
PAINT GREEN (-3400 2500);
DISPLAY INVISIBLE (-3400 2500);
FORCEPROP 1 LAST PATH I277
J 2
(-3073 2625);
DISPLAY 0.872340 (-3073 2625);
PAINT GREEN (-3073 2625);
DISPLAY INVISIBLE (-3073 2625);
FORCEPROP 2 LAST ROOM RISER1
J 0
(-3575 2675);
DISPLAY 0.829787 (-3575 2675);
PAINT RED (-3575 2675);
DISPLAY INVISIBLE (-3575 2675);
FORCEADD TAP..6
R 2
(-3075 2425);
FORCEPROP 3 LASTPIN (-3125 2425) SIG_NAME GMI_CPU1_G1_CPU0_G3_TX_DP<9>
J 0
(-3115 2435);
DISPLAY 0.659574 (-3115 2435);
PAINT MONO (-3115 2435);
DISPLAY INVISIBLE (-3115 2435);
FORCEPROP 1 LASTPIN (-3125 2425) BN 9
J 2
(-3073 2433);
DISPLAY 0.489362 (-3073 2433);
PAINT MONO (-3073 2433);
FORCEPROP 2 LAST CDS_LIB standard
J 0
(-3075 2425);
DISPLAY INVISIBLE (-3075 2425);
FORCEPROP 2 LAST BOM_COST IO_SLOT
J 0
(-3575 2525);
DISPLAY 0.829787 (-3575 2525);
DISPLAY INVISIBLE (-3575 2525);
FORCEPROP 1 LAST BODY_TYPE PLUMBING
J 2
(-3075 2375);
DISPLAY 0.702128 (-3075 2375);
PAINT GREEN (-3075 2375);
DISPLAY INVISIBLE (-3075 2375);
FORCEPROP 1 LAST HDL_TAP TRUE
J 2
(-3400 2300);
DISPLAY 0.702128 (-3400 2300);
PAINT GREEN (-3400 2300);
DISPLAY INVISIBLE (-3400 2300);
FORCEPROP 1 LAST PATH I280
J 2
(-3073 2425);
DISPLAY 0.872340 (-3073 2425);
PAINT GREEN (-3073 2425);
DISPLAY INVISIBLE (-3073 2425);
FORCEPROP 2 LAST ROOM RISER1
J 0
(-3575 2475);
DISPLAY 0.829787 (-3575 2475);
PAINT RED (-3575 2475);
DISPLAY INVISIBLE (-3575 2475);
FORCEADD TAP..6
R 2
(-3075 2325);
FORCEPROP 3 LASTPIN (-3125 2325) SIG_NAME GMI_CPU1_G1_CPU0_G3_TX_DP<8>
J 0
(-3115 2335);
DISPLAY 0.659574 (-3115 2335);
PAINT MONO (-3115 2335);
DISPLAY INVISIBLE (-3115 2335);
FORCEPROP 1 LASTPIN (-3125 2325) BN 8
J 2
(-3073 2333);
DISPLAY 0.489362 (-3073 2333);
PAINT MONO (-3073 2333);
FORCEPROP 2 LAST CDS_LIB standard
J 0
(-3075 2325);
DISPLAY INVISIBLE (-3075 2325);
FORCEPROP 2 LAST BOM_COST IO_SLOT
J 0
(-3575 2425);
DISPLAY 0.829787 (-3575 2425);
DISPLAY INVISIBLE (-3575 2425);
FORCEPROP 1 LAST BODY_TYPE PLUMBING
J 2
(-3075 2275);
DISPLAY 0.702128 (-3075 2275);
PAINT GREEN (-3075 2275);
DISPLAY INVISIBLE (-3075 2275);
FORCEPROP 1 LAST HDL_TAP TRUE
J 2
(-3400 2200);
DISPLAY 0.702128 (-3400 2200);
PAINT GREEN (-3400 2200);
DISPLAY INVISIBLE (-3400 2200);
FORCEPROP 1 LAST PATH I281
J 2
(-3073 2325);
DISPLAY 0.872340 (-3073 2325);
PAINT GREEN (-3073 2325);
DISPLAY INVISIBLE (-3073 2325);
FORCEPROP 2 LAST ROOM RISER1
J 0
(-3575 2375);
DISPLAY 0.829787 (-3575 2375);
PAINT RED (-3575 2375);
DISPLAY INVISIBLE (-3575 2375);
FORCEADD TAP..6
R 2
(-3075 2525);
FORCEPROP 3 LASTPIN (-3125 2525) SIG_NAME GMI_CPU1_G1_CPU0_G3_TX_DP<10>
J 0
(-3115 2535);
DISPLAY 0.659574 (-3115 2535);
PAINT MONO (-3115 2535);
DISPLAY INVISIBLE (-3115 2535);
FORCEPROP 1 LASTPIN (-3125 2525) BN 10
J 2
(-3073 2533);
DISPLAY 0.489362 (-3073 2533);
PAINT MONO (-3073 2533);
FORCEPROP 2 LAST CDS_LIB standard
J 0
(-3075 2525);
DISPLAY INVISIBLE (-3075 2525);
FORCEPROP 2 LAST BOM_COST IO_SLOT
J 0
(-3575 2625);
DISPLAY 0.829787 (-3575 2625);
DISPLAY INVISIBLE (-3575 2625);
FORCEPROP 1 LAST BODY_TYPE PLUMBING
J 2
(-3075 2475);
DISPLAY 0.702128 (-3075 2475);
PAINT GREEN (-3075 2475);
DISPLAY INVISIBLE (-3075 2475);
FORCEPROP 1 LAST HDL_TAP TRUE
J 2
(-3400 2400);
DISPLAY 0.702128 (-3400 2400);
PAINT GREEN (-3400 2400);
DISPLAY INVISIBLE (-3400 2400);
FORCEPROP 1 LAST PATH I282
J 2
(-3073 2525);
DISPLAY 0.872340 (-3073 2525);
PAINT GREEN (-3073 2525);
DISPLAY INVISIBLE (-3073 2525);
FORCEPROP 2 LAST ROOM RISER1
J 0
(-3575 2575);
DISPLAY 0.829787 (-3575 2575);
PAINT RED (-3575 2575);
DISPLAY INVISIBLE (-3575 2575);
FORCEADD TAP..6
R 2
(-3075 2225);
FORCEPROP 3 LASTPIN (-3125 2225) SIG_NAME GMI_CPU1_G1_CPU0_G3_TX_DP<7>
J 0
(-3115 2235);
DISPLAY 0.659574 (-3115 2235);
PAINT MONO (-3115 2235);
DISPLAY INVISIBLE (-3115 2235);
FORCEPROP 1 LASTPIN (-3125 2225) BN 7
J 2
(-3073 2233);
DISPLAY 0.489362 (-3073 2233);
PAINT MONO (-3073 2233);
FORCEPROP 2 LAST CDS_LIB standard
J 0
(-3075 2225);
DISPLAY INVISIBLE (-3075 2225);
FORCEPROP 2 LAST BOM_COST IO_SLOT
J 0
(-3575 2325);
DISPLAY 0.829787 (-3575 2325);
DISPLAY INVISIBLE (-3575 2325);
FORCEPROP 1 LAST BODY_TYPE PLUMBING
J 2
(-3075 2175);
DISPLAY 0.702128 (-3075 2175);
PAINT GREEN (-3075 2175);
DISPLAY INVISIBLE (-3075 2175);
FORCEPROP 1 LAST HDL_TAP TRUE
J 2
(-3400 2100);
DISPLAY 0.702128 (-3400 2100);
PAINT GREEN (-3400 2100);
DISPLAY INVISIBLE (-3400 2100);
FORCEPROP 1 LAST PATH I286
J 2
(-3073 2225);
DISPLAY 0.872340 (-3073 2225);
PAINT GREEN (-3073 2225);
DISPLAY INVISIBLE (-3073 2225);
FORCEPROP 2 LAST ROOM RISER1
J 0
(-3575 2275);
DISPLAY 0.829787 (-3575 2275);
PAINT RED (-3575 2275);
DISPLAY INVISIBLE (-3575 2275);
FORCEADD TAP..6
R 2
(-3075 2125);
FORCEPROP 3 LASTPIN (-3125 2125) SIG_NAME GMI_CPU1_G1_CPU0_G3_TX_DP<6>
J 0
(-3115 2135);
DISPLAY 0.659574 (-3115 2135);
PAINT MONO (-3115 2135);
DISPLAY INVISIBLE (-3115 2135);
FORCEPROP 1 LASTPIN (-3125 2125) BN 6
J 2
(-3073 2133);
DISPLAY 0.489362 (-3073 2133);
PAINT MONO (-3073 2133);
FORCEPROP 2 LAST CDS_LIB standard
J 0
(-3075 2125);
DISPLAY INVISIBLE (-3075 2125);
FORCEPROP 2 LAST BOM_COST IO_SLOT
J 0
(-3575 2225);
DISPLAY 0.829787 (-3575 2225);
DISPLAY INVISIBLE (-3575 2225);
FORCEPROP 1 LAST BODY_TYPE PLUMBING
J 2
(-3075 2075);
DISPLAY 0.702128 (-3075 2075);
PAINT GREEN (-3075 2075);
DISPLAY INVISIBLE (-3075 2075);
FORCEPROP 1 LAST HDL_TAP TRUE
J 2
(-3400 2000);
DISPLAY 0.702128 (-3400 2000);
PAINT GREEN (-3400 2000);
DISPLAY INVISIBLE (-3400 2000);
FORCEPROP 1 LAST PATH I287
J 2
(-3073 2125);
DISPLAY 0.872340 (-3073 2125);
PAINT GREEN (-3073 2125);
DISPLAY INVISIBLE (-3073 2125);
FORCEPROP 2 LAST ROOM RISER1
J 0
(-3575 2175);
DISPLAY 0.829787 (-3575 2175);
PAINT RED (-3575 2175);
DISPLAY INVISIBLE (-3575 2175);
FORCEADD TAP..6
R 2
(-3075 1925);
FORCEPROP 3 LASTPIN (-3125 1925) SIG_NAME GMI_CPU1_G1_CPU0_G3_TX_DP<4>
J 0
(-3115 1935);
DISPLAY 0.659574 (-3115 1935);
PAINT MONO (-3115 1935);
DISPLAY INVISIBLE (-3115 1935);
FORCEPROP 1 LASTPIN (-3125 1925) BN 4
J 2
(-3073 1933);
DISPLAY 0.489362 (-3073 1933);
PAINT MONO (-3073 1933);
FORCEPROP 2 LAST CDS_LIB standard
J 0
(-3075 1925);
DISPLAY INVISIBLE (-3075 1925);
FORCEPROP 2 LAST BOM_COST IO_SLOT
J 0
(-3575 2025);
DISPLAY 0.829787 (-3575 2025);
DISPLAY INVISIBLE (-3575 2025);
FORCEPROP 1 LAST BODY_TYPE PLUMBING
J 2
(-3075 1875);
DISPLAY 0.702128 (-3075 1875);
PAINT GREEN (-3075 1875);
DISPLAY INVISIBLE (-3075 1875);
FORCEPROP 1 LAST HDL_TAP TRUE
J 2
(-3400 1800);
DISPLAY 0.702128 (-3400 1800);
PAINT GREEN (-3400 1800);
DISPLAY INVISIBLE (-3400 1800);
FORCEPROP 1 LAST PATH I290
J 2
(-3073 1925);
DISPLAY 0.872340 (-3073 1925);
PAINT GREEN (-3073 1925);
DISPLAY INVISIBLE (-3073 1925);
FORCEPROP 2 LAST ROOM RISER1
J 0
(-3575 1975);
DISPLAY 0.829787 (-3575 1975);
PAINT RED (-3575 1975);
DISPLAY INVISIBLE (-3575 1975);
FORCEADD TAP..6
R 2
(-3075 1825);
FORCEPROP 3 LASTPIN (-3125 1825) SIG_NAME GMI_CPU1_G1_CPU0_G3_TX_DP<3>
J 0
(-3115 1835);
DISPLAY 0.659574 (-3115 1835);
PAINT MONO (-3115 1835);
DISPLAY INVISIBLE (-3115 1835);
FORCEPROP 1 LASTPIN (-3125 1825) BN 3
J 2
(-3073 1833);
DISPLAY 0.489362 (-3073 1833);
PAINT MONO (-3073 1833);
FORCEPROP 2 LAST CDS_LIB standard
J 0
(-3075 1825);
DISPLAY INVISIBLE (-3075 1825);
FORCEPROP 2 LAST BOM_COST IO_SLOT
J 0
(-3575 1925);
DISPLAY 0.829787 (-3575 1925);
DISPLAY INVISIBLE (-3575 1925);
FORCEPROP 1 LAST BODY_TYPE PLUMBING
J 2
(-3075 1775);
DISPLAY 0.702128 (-3075 1775);
PAINT GREEN (-3075 1775);
DISPLAY INVISIBLE (-3075 1775);
FORCEPROP 1 LAST HDL_TAP TRUE
J 2
(-3400 1700);
DISPLAY 0.702128 (-3400 1700);
PAINT GREEN (-3400 1700);
DISPLAY INVISIBLE (-3400 1700);
FORCEPROP 1 LAST PATH I291
J 2
(-3073 1825);
DISPLAY 0.872340 (-3073 1825);
PAINT GREEN (-3073 1825);
DISPLAY INVISIBLE (-3073 1825);
FORCEPROP 2 LAST ROOM RISER1
J 0
(-3575 1875);
DISPLAY 0.829787 (-3575 1875);
PAINT RED (-3575 1875);
DISPLAY INVISIBLE (-3575 1875);
FORCEADD TAP..6
R 2
(-3075 2025);
FORCEPROP 3 LASTPIN (-3125 2025) SIG_NAME GMI_CPU1_G1_CPU0_G3_TX_DP<5>
J 0
(-3115 2035);
DISPLAY 0.659574 (-3115 2035);
PAINT MONO (-3115 2035);
DISPLAY INVISIBLE (-3115 2035);
FORCEPROP 1 LASTPIN (-3125 2025) BN 5
J 2
(-3073 2033);
DISPLAY 0.489362 (-3073 2033);
PAINT MONO (-3073 2033);
FORCEPROP 2 LAST CDS_LIB standard
J 0
(-3075 2025);
DISPLAY INVISIBLE (-3075 2025);
FORCEPROP 2 LAST BOM_COST IO_SLOT
J 0
(-3575 2125);
DISPLAY 0.829787 (-3575 2125);
DISPLAY INVISIBLE (-3575 2125);
FORCEPROP 1 LAST BODY_TYPE PLUMBING
J 2
(-3075 1975);
DISPLAY 0.702128 (-3075 1975);
PAINT GREEN (-3075 1975);
DISPLAY INVISIBLE (-3075 1975);
FORCEPROP 1 LAST HDL_TAP TRUE
J 2
(-3400 1900);
DISPLAY 0.702128 (-3400 1900);
PAINT GREEN (-3400 1900);
DISPLAY INVISIBLE (-3400 1900);
FORCEPROP 1 LAST PATH I292
J 2
(-3073 2025);
DISPLAY 0.872340 (-3073 2025);
PAINT GREEN (-3073 2025);
DISPLAY INVISIBLE (-3073 2025);
FORCEPROP 2 LAST ROOM RISER1
J 0
(-3575 2075);
DISPLAY 0.829787 (-3575 2075);
PAINT RED (-3575 2075);
DISPLAY INVISIBLE (-3575 2075);
FORCEADD TAP..6
R 2
(-3075 1725);
FORCEPROP 3 LASTPIN (-3125 1725) SIG_NAME GMI_CPU1_G1_CPU0_G3_TX_DP<2>
J 0
(-3115 1735);
DISPLAY 0.659574 (-3115 1735);
PAINT MONO (-3115 1735);
DISPLAY INVISIBLE (-3115 1735);
FORCEPROP 1 LASTPIN (-3125 1725) BN 2
J 2
(-3073 1733);
DISPLAY 0.489362 (-3073 1733);
PAINT MONO (-3073 1733);
FORCEPROP 2 LAST CDS_LIB standard
J 0
(-3075 1725);
DISPLAY INVISIBLE (-3075 1725);
FORCEPROP 2 LAST BOM_COST IO_SLOT
J 0
(-3575 1825);
DISPLAY 0.829787 (-3575 1825);
DISPLAY INVISIBLE (-3575 1825);
FORCEPROP 1 LAST BODY_TYPE PLUMBING
J 2
(-3075 1675);
DISPLAY 0.702128 (-3075 1675);
PAINT GREEN (-3075 1675);
DISPLAY INVISIBLE (-3075 1675);
FORCEPROP 1 LAST HDL_TAP TRUE
J 2
(-3400 1600);
DISPLAY 0.702128 (-3400 1600);
PAINT GREEN (-3400 1600);
DISPLAY INVISIBLE (-3400 1600);
FORCEPROP 1 LAST PATH I296
J 2
(-3073 1725);
DISPLAY 0.872340 (-3073 1725);
PAINT GREEN (-3073 1725);
DISPLAY INVISIBLE (-3073 1725);
FORCEPROP 2 LAST ROOM RISER1
J 0
(-3575 1775);
DISPLAY 0.829787 (-3575 1775);
PAINT RED (-3575 1775);
DISPLAY INVISIBLE (-3575 1775);
FORCEADD TAP..6
R 2
(-3075 1625);
FORCEPROP 3 LASTPIN (-3125 1625) SIG_NAME GMI_CPU1_G1_CPU0_G3_TX_DP<1>
J 0
(-3115 1635);
DISPLAY 0.659574 (-3115 1635);
PAINT MONO (-3115 1635);
DISPLAY INVISIBLE (-3115 1635);
FORCEPROP 1 LASTPIN (-3125 1625) BN 1
J 2
(-3073 1633);
DISPLAY 0.489362 (-3073 1633);
PAINT MONO (-3073 1633);
FORCEPROP 2 LAST CDS_LIB standard
J 0
(-3075 1625);
DISPLAY INVISIBLE (-3075 1625);
FORCEPROP 2 LAST BOM_COST IO_SLOT
J 0
(-3575 1725);
DISPLAY 0.829787 (-3575 1725);
DISPLAY INVISIBLE (-3575 1725);
FORCEPROP 1 LAST BODY_TYPE PLUMBING
J 2
(-3075 1575);
DISPLAY 0.702128 (-3075 1575);
PAINT GREEN (-3075 1575);
DISPLAY INVISIBLE (-3075 1575);
FORCEPROP 1 LAST HDL_TAP TRUE
J 2
(-3400 1500);
DISPLAY 0.702128 (-3400 1500);
PAINT GREEN (-3400 1500);
DISPLAY INVISIBLE (-3400 1500);
FORCEPROP 1 LAST PATH I297
J 2
(-3073 1625);
DISPLAY 0.872340 (-3073 1625);
PAINT GREEN (-3073 1625);
DISPLAY INVISIBLE (-3073 1625);
FORCEPROP 2 LAST ROOM RISER1
J 0
(-3575 1675);
DISPLAY 0.829787 (-3575 1675);
PAINT RED (-3575 1675);
DISPLAY INVISIBLE (-3575 1675);
FORCEADD TAP..6
R 2
(-3075 1525);
FORCEPROP 3 LASTPIN (-3125 1525) SIG_NAME GMI_CPU1_G1_CPU0_G3_TX_DP<0>
J 0
(-3115 1535);
DISPLAY 0.659574 (-3115 1535);
PAINT MONO (-3115 1535);
DISPLAY INVISIBLE (-3115 1535);
FORCEPROP 1 LASTPIN (-3125 1525) BN 0
J 2
(-3073 1533);
DISPLAY 0.489362 (-3073 1533);
PAINT MONO (-3073 1533);
FORCEPROP 2 LAST CDS_LIB standard
J 0
(-3075 1525);
DISPLAY INVISIBLE (-3075 1525);
FORCEPROP 2 LAST BOM_COST IO_SLOT
J 0
(-3575 1625);
DISPLAY 0.829787 (-3575 1625);
DISPLAY INVISIBLE (-3575 1625);
FORCEPROP 1 LAST BODY_TYPE PLUMBING
J 2
(-3075 1475);
DISPLAY 0.702128 (-3075 1475);
PAINT GREEN (-3075 1475);
DISPLAY INVISIBLE (-3075 1475);
FORCEPROP 1 LAST HDL_TAP TRUE
J 2
(-3400 1400);
DISPLAY 0.702128 (-3400 1400);
PAINT GREEN (-3400 1400);
DISPLAY INVISIBLE (-3400 1400);
FORCEPROP 1 LAST PATH I298
J 2
(-3073 1525);
DISPLAY 0.872340 (-3073 1525);
PAINT GREEN (-3073 1525);
DISPLAY INVISIBLE (-3073 1525);
FORCEPROP 2 LAST ROOM RISER1
J 0
(-3575 1575);
DISPLAY 0.829787 (-3575 1575);
PAINT RED (-3575 1575);
DISPLAY INVISIBLE (-3575 1575);
FORCEADD TAP..6
(-6525 5750);
FORCEPROP 3 LASTPIN (-6475 5750) SIG_NAME GMI_CPU0_G2_CPU1_G0_TX_DP<15>
J 0
(-6465 5760);
DISPLAY 0.659574 (-6465 5760);
PAINT MONO (-6465 5760);
DISPLAY INVISIBLE (-6465 5760);
FORCEPROP 1 LASTPIN (-6475 5750) BN 15
J 0
(-6527 5758);
DISPLAY 0.489362 (-6527 5758);
PAINT MONO (-6527 5758);
FORCEPROP 2 LAST CDS_LIB mstr_standard
J 0
(-6525 5750);
DISPLAY INVISIBLE (-6525 5750);
FORCEPROP 1 LAST BODY_TYPE PLUMBING
J 0
(-6525 5700);
DISPLAY 0.574468 (-6525 5700);
PAINT GREEN (-6525 5700);
DISPLAY INVISIBLE (-6525 5700);
FORCEPROP 1 LAST HDL_TAP TRUE
J 0
(-6200 5625);
DISPLAY 0.574468 (-6200 5625);
PAINT GREEN (-6200 5625);
DISPLAY INVISIBLE (-6200 5625);
FORCEPROP 1 LAST PATH I300
J 0
(-6527 5750);
DISPLAY 0.872340 (-6527 5750);
PAINT GREEN (-6527 5750);
DISPLAY INVISIBLE (-6527 5750);
FORCEADD TAP..6
(-6525 5650);
FORCEPROP 3 LASTPIN (-6475 5650) SIG_NAME GMI_CPU0_G2_CPU1_G0_TX_DP<14>
J 0
(-6465 5660);
DISPLAY 0.659574 (-6465 5660);
PAINT MONO (-6465 5660);
DISPLAY INVISIBLE (-6465 5660);
FORCEPROP 1 LASTPIN (-6475 5650) BN 14
J 0
(-6527 5658);
DISPLAY 0.489362 (-6527 5658);
PAINT MONO (-6527 5658);
FORCEPROP 2 LAST CDS_LIB mstr_standard
J 0
(-6525 5650);
DISPLAY INVISIBLE (-6525 5650);
FORCEPROP 1 LAST BODY_TYPE PLUMBING
J 0
(-6525 5600);
DISPLAY 0.574468 (-6525 5600);
PAINT GREEN (-6525 5600);
DISPLAY INVISIBLE (-6525 5600);
FORCEPROP 1 LAST HDL_TAP TRUE
J 0
(-6200 5525);
DISPLAY 0.574468 (-6200 5525);
PAINT GREEN (-6200 5525);
DISPLAY INVISIBLE (-6200 5525);
FORCEPROP 1 LAST PATH I301
J 0
(-6527 5650);
DISPLAY 0.872340 (-6527 5650);
PAINT GREEN (-6527 5650);
DISPLAY INVISIBLE (-6527 5650);
FORCEADD TAP..6
(-6525 5550);
FORCEPROP 3 LASTPIN (-6475 5550) SIG_NAME GMI_CPU0_G2_CPU1_G0_TX_DP<13>
J 0
(-6465 5560);
DISPLAY 0.659574 (-6465 5560);
PAINT MONO (-6465 5560);
DISPLAY INVISIBLE (-6465 5560);
FORCEPROP 1 LASTPIN (-6475 5550) BN 13
J 0
(-6527 5558);
DISPLAY 0.489362 (-6527 5558);
PAINT MONO (-6527 5558);
FORCEPROP 2 LAST CDS_LIB mstr_standard
J 0
(-6525 5550);
DISPLAY INVISIBLE (-6525 5550);
FORCEPROP 1 LAST BODY_TYPE PLUMBING
J 0
(-6525 5500);
DISPLAY 0.574468 (-6525 5500);
PAINT GREEN (-6525 5500);
DISPLAY INVISIBLE (-6525 5500);
FORCEPROP 1 LAST HDL_TAP TRUE
J 0
(-6200 5425);
DISPLAY 0.574468 (-6200 5425);
PAINT GREEN (-6200 5425);
DISPLAY INVISIBLE (-6200 5425);
FORCEPROP 1 LAST PATH I303
J 0
(-6527 5550);
DISPLAY 0.872340 (-6527 5550);
PAINT GREEN (-6527 5550);
DISPLAY INVISIBLE (-6527 5550);
FORCEADD TAP..6
(-6525 5450);
FORCEPROP 3 LASTPIN (-6475 5450) SIG_NAME GMI_CPU0_G2_CPU1_G0_TX_DP<12>
J 0
(-6465 5460);
DISPLAY 0.659574 (-6465 5460);
PAINT MONO (-6465 5460);
DISPLAY INVISIBLE (-6465 5460);
FORCEPROP 1 LASTPIN (-6475 5450) BN 12
J 0
(-6527 5458);
DISPLAY 0.489362 (-6527 5458);
PAINT MONO (-6527 5458);
FORCEPROP 2 LAST CDS_LIB standard
J 0
(-6525 5450);
DISPLAY INVISIBLE (-6525 5450);
FORCEPROP 1 LAST BODY_TYPE PLUMBING
J 0
(-6525 5400);
DISPLAY 0.574468 (-6525 5400);
PAINT GREEN (-6525 5400);
DISPLAY INVISIBLE (-6525 5400);
FORCEPROP 1 LAST HDL_TAP TRUE
J 0
(-6200 5325);
DISPLAY 0.574468 (-6200 5325);
PAINT GREEN (-6200 5325);
DISPLAY INVISIBLE (-6200 5325);
FORCEPROP 1 LAST PATH I304
J 0
(-6527 5450);
DISPLAY 0.872340 (-6527 5450);
PAINT GREEN (-6527 5450);
DISPLAY INVISIBLE (-6527 5450);
FORCEADD TAP..6
(-6525 5250);
FORCEPROP 3 LASTPIN (-6475 5250) SIG_NAME GMI_CPU0_G2_CPU1_G0_TX_DP<10>
J 0
(-6465 5260);
DISPLAY 0.659574 (-6465 5260);
PAINT MONO (-6465 5260);
DISPLAY INVISIBLE (-6465 5260);
FORCEPROP 1 LASTPIN (-6475 5250) BN 10
J 0
(-6527 5258);
DISPLAY 0.489362 (-6527 5258);
PAINT MONO (-6527 5258);
FORCEPROP 2 LAST CDS_LIB standard
J 0
(-6525 5250);
DISPLAY INVISIBLE (-6525 5250);
FORCEPROP 1 LAST BODY_TYPE PLUMBING
J 0
(-6525 5200);
DISPLAY 0.574468 (-6525 5200);
PAINT GREEN (-6525 5200);
DISPLAY INVISIBLE (-6525 5200);
FORCEPROP 1 LAST HDL_TAP TRUE
J 0
(-6200 5125);
DISPLAY 0.574468 (-6200 5125);
PAINT GREEN (-6200 5125);
DISPLAY INVISIBLE (-6200 5125);
FORCEPROP 1 LAST PATH I308
J 0
(-6527 5250);
DISPLAY 0.872340 (-6527 5250);
PAINT GREEN (-6527 5250);
DISPLAY INVISIBLE (-6527 5250);
FORCEADD TAP..6
(-6525 5350);
FORCEPROP 3 LASTPIN (-6475 5350) SIG_NAME GMI_CPU0_G2_CPU1_G0_TX_DP<11>
J 0
(-6465 5360);
DISPLAY 0.659574 (-6465 5360);
PAINT MONO (-6465 5360);
DISPLAY INVISIBLE (-6465 5360);
FORCEPROP 1 LASTPIN (-6475 5350) BN 11
J 0
(-6527 5358);
DISPLAY 0.489362 (-6527 5358);
PAINT MONO (-6527 5358);
FORCEPROP 2 LAST CDS_LIB standard
J 0
(-6525 5350);
DISPLAY INVISIBLE (-6525 5350);
FORCEPROP 1 LAST BODY_TYPE PLUMBING
J 0
(-6525 5300);
DISPLAY 0.574468 (-6525 5300);
PAINT GREEN (-6525 5300);
DISPLAY INVISIBLE (-6525 5300);
FORCEPROP 1 LAST HDL_TAP TRUE
J 0
(-6200 5225);
DISPLAY 0.574468 (-6200 5225);
PAINT GREEN (-6200 5225);
DISPLAY INVISIBLE (-6200 5225);
FORCEPROP 1 LAST PATH I309
J 0
(-6527 5350);
DISPLAY 0.872340 (-6527 5350);
PAINT GREEN (-6527 5350);
DISPLAY INVISIBLE (-6527 5350);
FORCEADD TAP..6
(-6525 5150);
FORCEPROP 3 LASTPIN (-6475 5150) SIG_NAME GMI_CPU0_G2_CPU1_G0_TX_DP<9>
J 0
(-6465 5160);
DISPLAY 0.659574 (-6465 5160);
PAINT MONO (-6465 5160);
DISPLAY INVISIBLE (-6465 5160);
FORCEPROP 1 LASTPIN (-6475 5150) BN 9
J 0
(-6527 5158);
DISPLAY 0.489362 (-6527 5158);
PAINT MONO (-6527 5158);
FORCEPROP 2 LAST CDS_LIB standard
J 0
(-6525 5150);
DISPLAY INVISIBLE (-6525 5150);
FORCEPROP 1 LAST BODY_TYPE PLUMBING
J 0
(-6525 5100);
DISPLAY 0.574468 (-6525 5100);
PAINT GREEN (-6525 5100);
DISPLAY INVISIBLE (-6525 5100);
FORCEPROP 1 LAST HDL_TAP TRUE
J 0
(-6200 5025);
DISPLAY 0.574468 (-6200 5025);
PAINT GREEN (-6200 5025);
DISPLAY INVISIBLE (-6200 5025);
FORCEPROP 1 LAST PATH I310
J 0
(-6527 5150);
DISPLAY 0.872340 (-6527 5150);
PAINT GREEN (-6527 5150);
DISPLAY INVISIBLE (-6527 5150);
FORCEADD TAP..6
(-6525 5050);
FORCEPROP 3 LASTPIN (-6475 5050) SIG_NAME GMI_CPU0_G2_CPU1_G0_TX_DP<8>
J 0
(-6465 5060);
DISPLAY 0.659574 (-6465 5060);
PAINT MONO (-6465 5060);
DISPLAY INVISIBLE (-6465 5060);
FORCEPROP 1 LASTPIN (-6475 5050) BN 8
J 0
(-6527 5058);
DISPLAY 0.489362 (-6527 5058);
PAINT MONO (-6527 5058);
FORCEPROP 2 LAST CDS_LIB standard
J 0
(-6525 5050);
DISPLAY INVISIBLE (-6525 5050);
FORCEPROP 1 LAST BODY_TYPE PLUMBING
J 0
(-6525 5000);
DISPLAY 0.574468 (-6525 5000);
PAINT GREEN (-6525 5000);
DISPLAY INVISIBLE (-6525 5000);
FORCEPROP 1 LAST HDL_TAP TRUE
J 0
(-6200 4925);
DISPLAY 0.574468 (-6200 4925);
PAINT GREEN (-6200 4925);
DISPLAY INVISIBLE (-6200 4925);
FORCEPROP 1 LAST PATH I313
J 0
(-6527 5050);
DISPLAY 0.872340 (-6527 5050);
PAINT GREEN (-6527 5050);
DISPLAY INVISIBLE (-6527 5050);
FORCEADD TAP..6
(-6525 4950);
FORCEPROP 3 LASTPIN (-6475 4950) SIG_NAME GMI_CPU0_G2_CPU1_G0_TX_DP<7>
J 0
(-6465 4960);
DISPLAY 0.659574 (-6465 4960);
PAINT MONO (-6465 4960);
DISPLAY INVISIBLE (-6465 4960);
FORCEPROP 1 LASTPIN (-6475 4950) BN 7
J 0
(-6527 4958);
DISPLAY 0.489362 (-6527 4958);
PAINT MONO (-6527 4958);
FORCEPROP 2 LAST CDS_LIB standard
J 0
(-6525 4950);
DISPLAY INVISIBLE (-6525 4950);
FORCEPROP 1 LAST BODY_TYPE PLUMBING
J 0
(-6525 4900);
DISPLAY 0.574468 (-6525 4900);
PAINT GREEN (-6525 4900);
DISPLAY INVISIBLE (-6525 4900);
FORCEPROP 1 LAST HDL_TAP TRUE
J 0
(-6200 4825);
DISPLAY 0.574468 (-6200 4825);
PAINT GREEN (-6200 4825);
DISPLAY INVISIBLE (-6200 4825);
FORCEPROP 1 LAST PATH I314
J 0
(-6527 4950);
DISPLAY 0.872340 (-6527 4950);
PAINT GREEN (-6527 4950);
DISPLAY INVISIBLE (-6527 4950);
FORCEADD TAP..6
(-6525 4850);
FORCEPROP 3 LASTPIN (-6475 4850) SIG_NAME GMI_CPU0_G2_CPU1_G0_TX_DP<6>
J 0
(-6465 4860);
DISPLAY 0.659574 (-6465 4860);
PAINT MONO (-6465 4860);
DISPLAY INVISIBLE (-6465 4860);
FORCEPROP 1 LASTPIN (-6475 4850) BN 6
J 0
(-6527 4858);
DISPLAY 0.489362 (-6527 4858);
PAINT MONO (-6527 4858);
FORCEPROP 2 LAST CDS_LIB standard
J 0
(-6525 4850);
DISPLAY INVISIBLE (-6525 4850);
FORCEPROP 1 LAST BODY_TYPE PLUMBING
J 0
(-6525 4800);
DISPLAY 0.574468 (-6525 4800);
PAINT GREEN (-6525 4800);
DISPLAY INVISIBLE (-6525 4800);
FORCEPROP 1 LAST HDL_TAP TRUE
J 0
(-6200 4725);
DISPLAY 0.574468 (-6200 4725);
PAINT GREEN (-6200 4725);
DISPLAY INVISIBLE (-6200 4725);
FORCEPROP 1 LAST PATH I318
J 0
(-6527 4850);
DISPLAY 0.872340 (-6527 4850);
PAINT GREEN (-6527 4850);
DISPLAY INVISIBLE (-6527 4850);
FORCEADD TAP..6
(-6525 4750);
FORCEPROP 3 LASTPIN (-6475 4750) SIG_NAME GMI_CPU0_G2_CPU1_G0_TX_DP<5>
J 0
(-6465 4760);
DISPLAY 0.659574 (-6465 4760);
PAINT MONO (-6465 4760);
DISPLAY INVISIBLE (-6465 4760);
FORCEPROP 1 LASTPIN (-6475 4750) BN 5
J 0
(-6527 4758);
DISPLAY 0.489362 (-6527 4758);
PAINT MONO (-6527 4758);
FORCEPROP 2 LAST CDS_LIB standard
J 0
(-6525 4750);
DISPLAY INVISIBLE (-6525 4750);
FORCEPROP 1 LAST BODY_TYPE PLUMBING
J 0
(-6525 4700);
DISPLAY 0.574468 (-6525 4700);
PAINT GREEN (-6525 4700);
DISPLAY INVISIBLE (-6525 4700);
FORCEPROP 1 LAST HDL_TAP TRUE
J 0
(-6200 4625);
DISPLAY 0.574468 (-6200 4625);
PAINT GREEN (-6200 4625);
DISPLAY INVISIBLE (-6200 4625);
FORCEPROP 1 LAST PATH I319
J 0
(-6527 4750);
DISPLAY 0.872340 (-6527 4750);
PAINT GREEN (-6527 4750);
DISPLAY INVISIBLE (-6527 4750);
FORCEADD TAP..6
(-6525 4650);
FORCEPROP 3 LASTPIN (-6475 4650) SIG_NAME GMI_CPU0_G2_CPU1_G0_TX_DP<4>
J 0
(-6465 4660);
DISPLAY 0.659574 (-6465 4660);
PAINT MONO (-6465 4660);
DISPLAY INVISIBLE (-6465 4660);
FORCEPROP 1 LASTPIN (-6475 4650) BN 4
J 0
(-6527 4658);
DISPLAY 0.489362 (-6527 4658);
PAINT MONO (-6527 4658);
FORCEPROP 2 LAST CDS_LIB standard
J 0
(-6525 4650);
DISPLAY INVISIBLE (-6525 4650);
FORCEPROP 1 LAST BODY_TYPE PLUMBING
J 0
(-6525 4600);
DISPLAY 0.574468 (-6525 4600);
PAINT GREEN (-6525 4600);
DISPLAY INVISIBLE (-6525 4600);
FORCEPROP 1 LAST HDL_TAP TRUE
J 0
(-6200 4525);
DISPLAY 0.574468 (-6200 4525);
PAINT GREEN (-6200 4525);
DISPLAY INVISIBLE (-6200 4525);
FORCEPROP 1 LAST PATH I320
J 0
(-6527 4650);
DISPLAY 0.872340 (-6527 4650);
PAINT GREEN (-6527 4650);
DISPLAY INVISIBLE (-6527 4650);
FORCEADD TAP..6
(-6525 4550);
FORCEPROP 3 LASTPIN (-6475 4550) SIG_NAME GMI_CPU0_G2_CPU1_G0_TX_DP<3>
J 0
(-6465 4560);
DISPLAY 0.659574 (-6465 4560);
PAINT MONO (-6465 4560);
DISPLAY INVISIBLE (-6465 4560);
FORCEPROP 1 LASTPIN (-6475 4550) BN 3
J 0
(-6527 4558);
DISPLAY 0.489362 (-6527 4558);
PAINT MONO (-6527 4558);
FORCEPROP 2 LAST CDS_LIB standard
J 0
(-6525 4550);
DISPLAY INVISIBLE (-6525 4550);
FORCEPROP 1 LAST BODY_TYPE PLUMBING
J 0
(-6525 4500);
DISPLAY 0.574468 (-6525 4500);
PAINT GREEN (-6525 4500);
DISPLAY INVISIBLE (-6525 4500);
FORCEPROP 1 LAST HDL_TAP TRUE
J 0
(-6200 4425);
DISPLAY 0.574468 (-6200 4425);
PAINT GREEN (-6200 4425);
DISPLAY INVISIBLE (-6200 4425);
FORCEPROP 1 LAST PATH I323
J 0
(-6527 4550);
DISPLAY 0.872340 (-6527 4550);
PAINT GREEN (-6527 4550);
DISPLAY INVISIBLE (-6527 4550);
FORCEADD TAP..6
(-6525 4450);
FORCEPROP 3 LASTPIN (-6475 4450) SIG_NAME GMI_CPU0_G2_CPU1_G0_TX_DP<2>
J 0
(-6465 4460);
DISPLAY 0.659574 (-6465 4460);
PAINT MONO (-6465 4460);
DISPLAY INVISIBLE (-6465 4460);
FORCEPROP 1 LASTPIN (-6475 4450) BN 2
J 0
(-6527 4458);
DISPLAY 0.489362 (-6527 4458);
PAINT MONO (-6527 4458);
FORCEPROP 2 LAST CDS_LIB standard
J 0
(-6525 4450);
DISPLAY INVISIBLE (-6525 4450);
FORCEPROP 1 LAST BODY_TYPE PLUMBING
J 0
(-6525 4400);
DISPLAY 0.574468 (-6525 4400);
PAINT GREEN (-6525 4400);
DISPLAY INVISIBLE (-6525 4400);
FORCEPROP 1 LAST HDL_TAP TRUE
J 0
(-6200 4325);
DISPLAY 0.574468 (-6200 4325);
PAINT GREEN (-6200 4325);
DISPLAY INVISIBLE (-6200 4325);
FORCEPROP 1 LAST PATH I324
J 0
(-6527 4450);
DISPLAY 0.872340 (-6527 4450);
PAINT GREEN (-6527 4450);
DISPLAY INVISIBLE (-6527 4450);
FORCEADD TAP..6
(-6525 4250);
FORCEPROP 3 LASTPIN (-6475 4250) SIG_NAME GMI_CPU0_G2_CPU1_G0_TX_DP<0>
J 0
(-6465 4260);
DISPLAY 0.659574 (-6465 4260);
PAINT MONO (-6465 4260);
DISPLAY INVISIBLE (-6465 4260);
FORCEPROP 1 LASTPIN (-6475 4250) BN 0
J 0
(-6527 4258);
DISPLAY 0.489362 (-6527 4258);
PAINT MONO (-6527 4258);
FORCEPROP 2 LAST CDS_LIB standard
J 0
(-6525 4250);
DISPLAY INVISIBLE (-6525 4250);
FORCEPROP 1 LAST BODY_TYPE PLUMBING
J 0
(-6525 4200);
DISPLAY 0.574468 (-6525 4200);
PAINT GREEN (-6525 4200);
DISPLAY INVISIBLE (-6525 4200);
FORCEPROP 1 LAST HDL_TAP TRUE
J 0
(-6200 4125);
DISPLAY 0.574468 (-6200 4125);
PAINT GREEN (-6200 4125);
DISPLAY INVISIBLE (-6200 4125);
FORCEPROP 1 LAST PATH I328
J 0
(-6527 4250);
DISPLAY 0.872340 (-6527 4250);
PAINT GREEN (-6527 4250);
DISPLAY INVISIBLE (-6527 4250);
FORCEADD TAP..6
(-6525 4350);
FORCEPROP 3 LASTPIN (-6475 4350) SIG_NAME GMI_CPU0_G2_CPU1_G0_TX_DP<1>
J 0
(-6465 4360);
DISPLAY 0.659574 (-6465 4360);
PAINT MONO (-6465 4360);
DISPLAY INVISIBLE (-6465 4360);
FORCEPROP 1 LASTPIN (-6475 4350) BN 1
J 0
(-6527 4358);
DISPLAY 0.489362 (-6527 4358);
PAINT MONO (-6527 4358);
FORCEPROP 2 LAST CDS_LIB standard
J 0
(-6525 4350);
DISPLAY INVISIBLE (-6525 4350);
FORCEPROP 1 LAST BODY_TYPE PLUMBING
J 0
(-6525 4300);
DISPLAY 0.574468 (-6525 4300);
PAINT GREEN (-6525 4300);
DISPLAY INVISIBLE (-6525 4300);
FORCEPROP 1 LAST HDL_TAP TRUE
J 0
(-6200 4225);
DISPLAY 0.574468 (-6200 4225);
PAINT GREEN (-6200 4225);
DISPLAY INVISIBLE (-6200 4225);
FORCEPROP 1 LAST PATH I329
J 0
(-6527 4350);
DISPLAY 0.872340 (-6527 4350);
PAINT GREEN (-6527 4350);
DISPLAY INVISIBLE (-6527 4350);
FORCEADD OFFPAGE..1
(-7725 5975);
FORCEPROP 2 LAST $XR0 23 
J 0
(-7946 5975);
DISPLAY 0.638298 (-7946 5975);
PAINT MONO (-7946 5975);
FORCEPROP 2 LAST PATH I333
J 0
(-7925 6025);
DISPLAY 1.021277 (-7925 6025);
DISPLAY INVISIBLE (-7925 6025);
FORCEPROP 1 LAST COMMENT_BODY TRUE
J 0
(-7600 5875);
DISPLAY 0.872340 (-7600 5875);
PAINT GREEN (-7600 5875);
DISPLAY INVISIBLE (-7600 5875);
FORCEPROP 1 LAST OFFPAGE TRUE
J 0
(-7400 5850);
DISPLAY 0.872340 (-7400 5850);
PAINT GREEN (-7400 5850);
DISPLAY INVISIBLE (-7400 5850);
FORCEPROP 2 LAST CDS_LIB standard
J 0
(-7725 5975);
DISPLAY INVISIBLE (-7725 5975);
FORCEADD TAP..6
(-6500 3025);
FORCEPROP 3 LASTPIN (-6450 3025) SIG_NAME GMI_CPU0_G3_CPU1_G1_TX_DP<15>
J 0
(-6440 3035);
DISPLAY 0.659574 (-6440 3035);
PAINT MONO (-6440 3035);
DISPLAY INVISIBLE (-6440 3035);
FORCEPROP 1 LASTPIN (-6450 3025) BN 15
J 0
(-6502 3033);
DISPLAY 0.489362 (-6502 3033);
PAINT MONO (-6502 3033);
FORCEPROP 2 LAST CDS_LIB mstr_standard
J 0
(-6500 3025);
DISPLAY INVISIBLE (-6500 3025);
FORCEPROP 1 LAST BODY_TYPE PLUMBING
J 0
(-6500 2975);
DISPLAY 0.574468 (-6500 2975);
PAINT GREEN (-6500 2975);
DISPLAY INVISIBLE (-6500 2975);
FORCEPROP 1 LAST HDL_TAP TRUE
J 0
(-6175 2900);
DISPLAY 0.574468 (-6175 2900);
PAINT GREEN (-6175 2900);
DISPLAY INVISIBLE (-6175 2900);
FORCEPROP 1 LAST PATH I334
J 0
(-6502 3025);
DISPLAY 0.872340 (-6502 3025);
PAINT GREEN (-6502 3025);
DISPLAY INVISIBLE (-6502 3025);
FORCEADD TAP..6
(-6500 2925);
FORCEPROP 3 LASTPIN (-6450 2925) SIG_NAME GMI_CPU0_G3_CPU1_G1_TX_DP<14>
J 0
(-6440 2935);
DISPLAY 0.659574 (-6440 2935);
PAINT MONO (-6440 2935);
DISPLAY INVISIBLE (-6440 2935);
FORCEPROP 1 LASTPIN (-6450 2925) BN 14
J 0
(-6502 2933);
DISPLAY 0.489362 (-6502 2933);
PAINT MONO (-6502 2933);
FORCEPROP 2 LAST CDS_LIB mstr_standard
J 0
(-6500 2925);
DISPLAY INVISIBLE (-6500 2925);
FORCEPROP 1 LAST BODY_TYPE PLUMBING
J 0
(-6500 2875);
DISPLAY 0.574468 (-6500 2875);
PAINT GREEN (-6500 2875);
DISPLAY INVISIBLE (-6500 2875);
FORCEPROP 1 LAST HDL_TAP TRUE
J 0
(-6175 2800);
DISPLAY 0.574468 (-6175 2800);
PAINT GREEN (-6175 2800);
DISPLAY INVISIBLE (-6175 2800);
FORCEPROP 1 LAST PATH I335
J 0
(-6502 2925);
DISPLAY 0.872340 (-6502 2925);
PAINT GREEN (-6502 2925);
DISPLAY INVISIBLE (-6502 2925);
FORCEADD TAP..6
(-6500 2825);
FORCEPROP 3 LASTPIN (-6450 2825) SIG_NAME GMI_CPU0_G3_CPU1_G1_TX_DP<13>
J 0
(-6440 2835);
DISPLAY 0.659574 (-6440 2835);
PAINT MONO (-6440 2835);
DISPLAY INVISIBLE (-6440 2835);
FORCEPROP 1 LASTPIN (-6450 2825) BN 13
J 0
(-6502 2833);
DISPLAY 0.489362 (-6502 2833);
PAINT MONO (-6502 2833);
FORCEPROP 2 LAST CDS_LIB mstr_standard
J 0
(-6500 2825);
DISPLAY INVISIBLE (-6500 2825);
FORCEPROP 1 LAST BODY_TYPE PLUMBING
J 0
(-6500 2775);
DISPLAY 0.574468 (-6500 2775);
PAINT GREEN (-6500 2775);
DISPLAY INVISIBLE (-6500 2775);
FORCEPROP 1 LAST HDL_TAP TRUE
J 0
(-6175 2700);
DISPLAY 0.574468 (-6175 2700);
PAINT GREEN (-6175 2700);
DISPLAY INVISIBLE (-6175 2700);
FORCEPROP 1 LAST PATH I336
J 0
(-6502 2825);
DISPLAY 0.872340 (-6502 2825);
PAINT GREEN (-6502 2825);
DISPLAY INVISIBLE (-6502 2825);
FORCEADD TAP..6
(-6500 2725);
FORCEPROP 3 LASTPIN (-6450 2725) SIG_NAME GMI_CPU0_G3_CPU1_G1_TX_DP<12>
J 0
(-6440 2735);
DISPLAY 0.659574 (-6440 2735);
PAINT MONO (-6440 2735);
DISPLAY INVISIBLE (-6440 2735);
FORCEPROP 1 LASTPIN (-6450 2725) BN 12
J 0
(-6502 2733);
DISPLAY 0.489362 (-6502 2733);
PAINT MONO (-6502 2733);
FORCEPROP 2 LAST CDS_LIB standard
J 0
(-6500 2725);
DISPLAY INVISIBLE (-6500 2725);
FORCEPROP 1 LAST BODY_TYPE PLUMBING
J 0
(-6500 2675);
DISPLAY 0.574468 (-6500 2675);
PAINT GREEN (-6500 2675);
DISPLAY INVISIBLE (-6500 2675);
FORCEPROP 1 LAST HDL_TAP TRUE
J 0
(-6175 2600);
DISPLAY 0.574468 (-6175 2600);
PAINT GREEN (-6175 2600);
DISPLAY INVISIBLE (-6175 2600);
FORCEPROP 1 LAST PATH I339
J 0
(-6502 2725);
DISPLAY 0.872340 (-6502 2725);
PAINT GREEN (-6502 2725);
DISPLAY INVISIBLE (-6502 2725);
FORCEADD TAP..6
(-6500 2625);
FORCEPROP 3 LASTPIN (-6450 2625) SIG_NAME GMI_CPU0_G3_CPU1_G1_TX_DP<11>
J 0
(-6440 2635);
DISPLAY 0.659574 (-6440 2635);
PAINT MONO (-6440 2635);
DISPLAY INVISIBLE (-6440 2635);
FORCEPROP 1 LASTPIN (-6450 2625) BN 11
J 0
(-6502 2633);
DISPLAY 0.489362 (-6502 2633);
PAINT MONO (-6502 2633);
FORCEPROP 2 LAST CDS_LIB standard
J 0
(-6500 2625);
DISPLAY INVISIBLE (-6500 2625);
FORCEPROP 1 LAST BODY_TYPE PLUMBING
J 0
(-6500 2575);
DISPLAY 0.574468 (-6500 2575);
PAINT GREEN (-6500 2575);
DISPLAY INVISIBLE (-6500 2575);
FORCEPROP 1 LAST HDL_TAP TRUE
J 0
(-6175 2500);
DISPLAY 0.574468 (-6175 2500);
PAINT GREEN (-6175 2500);
DISPLAY INVISIBLE (-6175 2500);
FORCEPROP 1 LAST PATH I340
J 0
(-6502 2625);
DISPLAY 0.872340 (-6502 2625);
PAINT GREEN (-6502 2625);
DISPLAY INVISIBLE (-6502 2625);
FORCEADD TAP..6
(-6500 2525);
FORCEPROP 3 LASTPIN (-6450 2525) SIG_NAME GMI_CPU0_G3_CPU1_G1_TX_DP<10>
J 0
(-6440 2535);
DISPLAY 0.659574 (-6440 2535);
PAINT MONO (-6440 2535);
DISPLAY INVISIBLE (-6440 2535);
FORCEPROP 1 LASTPIN (-6450 2525) BN 10
J 0
(-6502 2533);
DISPLAY 0.489362 (-6502 2533);
PAINT MONO (-6502 2533);
FORCEPROP 2 LAST CDS_LIB standard
J 0
(-6500 2525);
DISPLAY INVISIBLE (-6500 2525);
FORCEPROP 1 LAST BODY_TYPE PLUMBING
J 0
(-6500 2475);
DISPLAY 0.574468 (-6500 2475);
PAINT GREEN (-6500 2475);
DISPLAY INVISIBLE (-6500 2475);
FORCEPROP 1 LAST HDL_TAP TRUE
J 0
(-6175 2400);
DISPLAY 0.574468 (-6175 2400);
PAINT GREEN (-6175 2400);
DISPLAY INVISIBLE (-6175 2400);
FORCEPROP 1 LAST PATH I344
J 0
(-6502 2525);
DISPLAY 0.872340 (-6502 2525);
PAINT GREEN (-6502 2525);
DISPLAY INVISIBLE (-6502 2525);
FORCEADD TAP..6
(-6500 2425);
FORCEPROP 3 LASTPIN (-6450 2425) SIG_NAME GMI_CPU0_G3_CPU1_G1_TX_DP<9>
J 0
(-6440 2435);
DISPLAY 0.659574 (-6440 2435);
PAINT MONO (-6440 2435);
DISPLAY INVISIBLE (-6440 2435);
FORCEPROP 1 LASTPIN (-6450 2425) BN 9
J 0
(-6502 2433);
DISPLAY 0.489362 (-6502 2433);
PAINT MONO (-6502 2433);
FORCEPROP 2 LAST CDS_LIB standard
J 0
(-6500 2425);
DISPLAY INVISIBLE (-6500 2425);
FORCEPROP 1 LAST BODY_TYPE PLUMBING
J 0
(-6500 2375);
DISPLAY 0.574468 (-6500 2375);
PAINT GREEN (-6500 2375);
DISPLAY INVISIBLE (-6500 2375);
FORCEPROP 1 LAST HDL_TAP TRUE
J 0
(-6175 2300);
DISPLAY 0.574468 (-6175 2300);
PAINT GREEN (-6175 2300);
DISPLAY INVISIBLE (-6175 2300);
FORCEPROP 1 LAST PATH I345
J 0
(-6502 2425);
DISPLAY 0.872340 (-6502 2425);
PAINT GREEN (-6502 2425);
DISPLAY INVISIBLE (-6502 2425);
FORCEADD TAP..6
(-6500 2325);
FORCEPROP 3 LASTPIN (-6450 2325) SIG_NAME GMI_CPU0_G3_CPU1_G1_TX_DP<8>
J 0
(-6440 2335);
DISPLAY 0.659574 (-6440 2335);
PAINT MONO (-6440 2335);
DISPLAY INVISIBLE (-6440 2335);
FORCEPROP 1 LASTPIN (-6450 2325) BN 8
J 0
(-6502 2333);
DISPLAY 0.489362 (-6502 2333);
PAINT MONO (-6502 2333);
FORCEPROP 2 LAST CDS_LIB standard
J 0
(-6500 2325);
DISPLAY INVISIBLE (-6500 2325);
FORCEPROP 1 LAST BODY_TYPE PLUMBING
J 0
(-6500 2275);
DISPLAY 0.574468 (-6500 2275);
PAINT GREEN (-6500 2275);
DISPLAY INVISIBLE (-6500 2275);
FORCEPROP 1 LAST HDL_TAP TRUE
J 0
(-6175 2200);
DISPLAY 0.574468 (-6175 2200);
PAINT GREEN (-6175 2200);
DISPLAY INVISIBLE (-6175 2200);
FORCEPROP 1 LAST PATH I346
J 0
(-6502 2325);
DISPLAY 0.872340 (-6502 2325);
PAINT GREEN (-6502 2325);
DISPLAY INVISIBLE (-6502 2325);
FORCEADD TAP..6
(-6500 2225);
FORCEPROP 3 LASTPIN (-6450 2225) SIG_NAME GMI_CPU0_G3_CPU1_G1_TX_DP<7>
J 0
(-6440 2235);
DISPLAY 0.659574 (-6440 2235);
PAINT MONO (-6440 2235);
DISPLAY INVISIBLE (-6440 2235);
FORCEPROP 1 LASTPIN (-6450 2225) BN 7
J 0
(-6502 2233);
DISPLAY 0.489362 (-6502 2233);
PAINT MONO (-6502 2233);
FORCEPROP 2 LAST CDS_LIB standard
J 0
(-6500 2225);
DISPLAY INVISIBLE (-6500 2225);
FORCEPROP 1 LAST BODY_TYPE PLUMBING
J 0
(-6500 2175);
DISPLAY 0.574468 (-6500 2175);
PAINT GREEN (-6500 2175);
DISPLAY INVISIBLE (-6500 2175);
FORCEPROP 1 LAST HDL_TAP TRUE
J 0
(-6175 2100);
DISPLAY 0.574468 (-6175 2100);
PAINT GREEN (-6175 2100);
DISPLAY INVISIBLE (-6175 2100);
FORCEPROP 1 LAST PATH I349
J 0
(-6502 2225);
DISPLAY 0.872340 (-6502 2225);
PAINT GREEN (-6502 2225);
DISPLAY INVISIBLE (-6502 2225);
FORCEADD TAP..6
(-6500 2125);
FORCEPROP 3 LASTPIN (-6450 2125) SIG_NAME GMI_CPU0_G3_CPU1_G1_TX_DP<6>
J 0
(-6440 2135);
DISPLAY 0.659574 (-6440 2135);
PAINT MONO (-6440 2135);
DISPLAY INVISIBLE (-6440 2135);
FORCEPROP 1 LASTPIN (-6450 2125) BN 6
J 0
(-6502 2133);
DISPLAY 0.489362 (-6502 2133);
PAINT MONO (-6502 2133);
FORCEPROP 2 LAST CDS_LIB standard
J 0
(-6500 2125);
DISPLAY INVISIBLE (-6500 2125);
FORCEPROP 1 LAST BODY_TYPE PLUMBING
J 0
(-6500 2075);
DISPLAY 0.574468 (-6500 2075);
PAINT GREEN (-6500 2075);
DISPLAY INVISIBLE (-6500 2075);
FORCEPROP 1 LAST HDL_TAP TRUE
J 0
(-6175 2000);
DISPLAY 0.574468 (-6175 2000);
PAINT GREEN (-6175 2000);
DISPLAY INVISIBLE (-6175 2000);
FORCEPROP 1 LAST PATH I350
J 0
(-6502 2125);
DISPLAY 0.872340 (-6502 2125);
PAINT GREEN (-6502 2125);
DISPLAY INVISIBLE (-6502 2125);
FORCEADD OFFPAGE..1
(-7600 3250);
FORCEPROP 2 LASTPIN (-7550 3250) SIG_NAME GMI_CPU0_G3_CPU1_G1_TX_DP<0:15>
J 0
(-7535 3260);
DISPLAY 0.489362 (-7535 3260);
FORCEPROP 2 LAST $XR0 23 
J 0
(-7821 3250);
DISPLAY 0.638298 (-7821 3250);
PAINT MONO (-7821 3250);
FORCEPROP 2 LAST CDS_LIB standard
J 0
(-7600 3250);
DISPLAY INVISIBLE (-7600 3250);
FORCEPROP 1 LAST OFFPAGE TRUE
J 0
(-7275 3125);
DISPLAY 0.872340 (-7275 3125);
PAINT GREEN (-7275 3125);
DISPLAY INVISIBLE (-7275 3125);
FORCEPROP 1 LAST COMMENT_BODY TRUE
J 0
(-7475 3150);
DISPLAY 0.872340 (-7475 3150);
PAINT GREEN (-7475 3150);
DISPLAY INVISIBLE (-7475 3150);
FORCEPROP 2 LAST PATH I355
J 0
(-7800 3300);
DISPLAY 1.021277 (-7800 3300);
DISPLAY INVISIBLE (-7800 3300);
FORCEADD TAP..6
(-6500 2025);
FORCEPROP 3 LASTPIN (-6450 2025) SIG_NAME GMI_CPU0_G3_CPU1_G1_TX_DP<5>
J 0
(-6440 2035);
DISPLAY 0.659574 (-6440 2035);
PAINT MONO (-6440 2035);
DISPLAY INVISIBLE (-6440 2035);
FORCEPROP 1 LASTPIN (-6450 2025) BN 5
J 0
(-6502 2033);
DISPLAY 0.489362 (-6502 2033);
PAINT MONO (-6502 2033);
FORCEPROP 2 LAST CDS_LIB standard
J 0
(-6500 2025);
DISPLAY INVISIBLE (-6500 2025);
FORCEPROP 1 LAST BODY_TYPE PLUMBING
J 0
(-6500 1975);
DISPLAY 0.574468 (-6500 1975);
PAINT GREEN (-6500 1975);
DISPLAY INVISIBLE (-6500 1975);
FORCEPROP 1 LAST HDL_TAP TRUE
J 0
(-6175 1900);
DISPLAY 0.574468 (-6175 1900);
PAINT GREEN (-6175 1900);
DISPLAY INVISIBLE (-6175 1900);
FORCEPROP 1 LAST PATH I356
J 0
(-6502 2025);
DISPLAY 0.872340 (-6502 2025);
PAINT GREEN (-6502 2025);
DISPLAY INVISIBLE (-6502 2025);
FORCEADD TAP..6
(-6500 1925);
FORCEPROP 3 LASTPIN (-6450 1925) SIG_NAME GMI_CPU0_G3_CPU1_G1_TX_DP<4>
J 0
(-6440 1935);
DISPLAY 0.659574 (-6440 1935);
PAINT MONO (-6440 1935);
DISPLAY INVISIBLE (-6440 1935);
FORCEPROP 1 LASTPIN (-6450 1925) BN 4
J 0
(-6502 1933);
DISPLAY 0.489362 (-6502 1933);
PAINT MONO (-6502 1933);
FORCEPROP 2 LAST CDS_LIB standard
J 0
(-6500 1925);
DISPLAY INVISIBLE (-6500 1925);
FORCEPROP 1 LAST BODY_TYPE PLUMBING
J 0
(-6500 1875);
DISPLAY 0.574468 (-6500 1875);
PAINT GREEN (-6500 1875);
DISPLAY INVISIBLE (-6500 1875);
FORCEPROP 1 LAST HDL_TAP TRUE
J 0
(-6175 1800);
DISPLAY 0.574468 (-6175 1800);
PAINT GREEN (-6175 1800);
DISPLAY INVISIBLE (-6175 1800);
FORCEPROP 1 LAST PATH I357
J 0
(-6502 1925);
DISPLAY 0.872340 (-6502 1925);
PAINT GREEN (-6502 1925);
DISPLAY INVISIBLE (-6502 1925);
FORCEADD TAP..6
(-6500 1825);
FORCEPROP 3 LASTPIN (-6450 1825) SIG_NAME GMI_CPU0_G3_CPU1_G1_TX_DP<3>
J 0
(-6440 1835);
DISPLAY 0.659574 (-6440 1835);
PAINT MONO (-6440 1835);
DISPLAY INVISIBLE (-6440 1835);
FORCEPROP 1 LASTPIN (-6450 1825) BN 3
J 0
(-6502 1833);
DISPLAY 0.489362 (-6502 1833);
PAINT MONO (-6502 1833);
FORCEPROP 2 LAST CDS_LIB standard
J 0
(-6500 1825);
DISPLAY INVISIBLE (-6500 1825);
FORCEPROP 1 LAST BODY_TYPE PLUMBING
J 0
(-6500 1775);
DISPLAY 0.574468 (-6500 1775);
PAINT GREEN (-6500 1775);
DISPLAY INVISIBLE (-6500 1775);
FORCEPROP 1 LAST HDL_TAP TRUE
J 0
(-6175 1700);
DISPLAY 0.574468 (-6175 1700);
PAINT GREEN (-6175 1700);
DISPLAY INVISIBLE (-6175 1700);
FORCEPROP 1 LAST PATH I358
J 0
(-6502 1825);
DISPLAY 0.872340 (-6502 1825);
PAINT GREEN (-6502 1825);
DISPLAY INVISIBLE (-6502 1825);
FORCEADD TAP..6
(-6500 1725);
FORCEPROP 3 LASTPIN (-6450 1725) SIG_NAME GMI_CPU0_G3_CPU1_G1_TX_DP<2>
J 0
(-6440 1735);
DISPLAY 0.659574 (-6440 1735);
PAINT MONO (-6440 1735);
DISPLAY INVISIBLE (-6440 1735);
FORCEPROP 1 LASTPIN (-6450 1725) BN 2
J 0
(-6502 1733);
DISPLAY 0.489362 (-6502 1733);
PAINT MONO (-6502 1733);
FORCEPROP 2 LAST CDS_LIB standard
J 0
(-6500 1725);
DISPLAY INVISIBLE (-6500 1725);
FORCEPROP 1 LAST BODY_TYPE PLUMBING
J 0
(-6500 1675);
DISPLAY 0.574468 (-6500 1675);
PAINT GREEN (-6500 1675);
DISPLAY INVISIBLE (-6500 1675);
FORCEPROP 1 LAST HDL_TAP TRUE
J 0
(-6175 1600);
DISPLAY 0.574468 (-6175 1600);
PAINT GREEN (-6175 1600);
DISPLAY INVISIBLE (-6175 1600);
FORCEPROP 1 LAST PATH I361
J 0
(-6502 1725);
DISPLAY 0.872340 (-6502 1725);
PAINT GREEN (-6502 1725);
DISPLAY INVISIBLE (-6502 1725);
FORCEADD TAP..6
(-6500 1625);
FORCEPROP 3 LASTPIN (-6450 1625) SIG_NAME GMI_CPU0_G3_CPU1_G1_TX_DP<1>
J 0
(-6440 1635);
DISPLAY 0.659574 (-6440 1635);
PAINT MONO (-6440 1635);
DISPLAY INVISIBLE (-6440 1635);
FORCEPROP 1 LASTPIN (-6450 1625) BN 1
J 0
(-6502 1633);
DISPLAY 0.489362 (-6502 1633);
PAINT MONO (-6502 1633);
FORCEPROP 2 LAST CDS_LIB standard
J 0
(-6500 1625);
DISPLAY INVISIBLE (-6500 1625);
FORCEPROP 1 LAST BODY_TYPE PLUMBING
J 0
(-6500 1575);
DISPLAY 0.574468 (-6500 1575);
PAINT GREEN (-6500 1575);
DISPLAY INVISIBLE (-6500 1575);
FORCEPROP 1 LAST HDL_TAP TRUE
J 0
(-6175 1500);
DISPLAY 0.574468 (-6175 1500);
PAINT GREEN (-6175 1500);
DISPLAY INVISIBLE (-6175 1500);
FORCEPROP 1 LAST PATH I362
J 0
(-6502 1625);
DISPLAY 0.872340 (-6502 1625);
PAINT GREEN (-6502 1625);
DISPLAY INVISIBLE (-6502 1625);
FORCEADD TAP..6
(-6500 1525);
FORCEPROP 3 LASTPIN (-6450 1525) SIG_NAME GMI_CPU0_G3_CPU1_G1_TX_DP<0>
J 0
(-6440 1535);
DISPLAY 0.659574 (-6440 1535);
PAINT MONO (-6440 1535);
DISPLAY INVISIBLE (-6440 1535);
FORCEPROP 1 LASTPIN (-6450 1525) BN 0
J 0
(-6502 1533);
DISPLAY 0.489362 (-6502 1533);
PAINT MONO (-6502 1533);
FORCEPROP 2 LAST CDS_LIB standard
J 0
(-6500 1525);
DISPLAY INVISIBLE (-6500 1525);
FORCEPROP 1 LAST BODY_TYPE PLUMBING
J 0
(-6500 1475);
DISPLAY 0.574468 (-6500 1475);
PAINT GREEN (-6500 1475);
DISPLAY INVISIBLE (-6500 1475);
FORCEPROP 1 LAST HDL_TAP TRUE
J 0
(-6175 1400);
DISPLAY 0.574468 (-6175 1400);
PAINT GREEN (-6175 1400);
DISPLAY INVISIBLE (-6175 1400);
FORCEPROP 1 LAST PATH I366
J 0
(-6502 1525);
DISPLAY 0.872340 (-6502 1525);
PAINT GREEN (-6502 1525);
DISPLAY INVISIBLE (-6502 1525);
FORCEADD OFFPAGE..2
(-1825 5925);
FORCEPROP 2 LAST $XR0 23 
J 0
(-1636 5925);
DISPLAY 0.638298 (-1636 5925);
PAINT MONO (-1636 5925);
FORCEPROP 2 LAST CDS_LIB standard
J 0
(-1825 5925);
DISPLAY INVISIBLE (-1825 5925);
FORCEPROP 1 LAST OFFPAGE TRUE
J 0
(-1500 5800);
DISPLAY 0.872340 (-1500 5800);
PAINT GREEN (-1500 5800);
DISPLAY INVISIBLE (-1500 5800);
FORCEPROP 1 LAST COMMENT_BODY TRUE
J 0
(-1870 5830);
DISPLAY 0.872340 (-1870 5830);
PAINT GREEN (-1870 5830);
DISPLAY INVISIBLE (-1870 5830);
FORCEPROP 2 LAST PATH I436
J 0
(-1625 5975);
DISPLAY 1.021277 (-1625 5975);
DISPLAY INVISIBLE (-1625 5975);
FORCEADD TAP..6
R 2
(-2950 5700);
FORCEPROP 3 LASTPIN (-3000 5700) SIG_NAME GMI_CPU1_G0_CPU0_G2_TX_DN<15>
J 0
(-2990 5710);
DISPLAY 0.659574 (-2990 5710);
PAINT MONO (-2990 5710);
DISPLAY INVISIBLE (-2990 5710);
FORCEPROP 1 LASTPIN (-3000 5700) BN 15
J 2
(-2948 5708);
DISPLAY 0.489362 (-2948 5708);
PAINT MONO (-2948 5708);
FORCEPROP 2 LAST CDS_LIB mstr_standard
J 0
(-2950 5700);
DISPLAY INVISIBLE (-2950 5700);
FORCEPROP 2 LAST BOM_COST IO_SLOT
J 0
(-3450 5800);
DISPLAY 0.829787 (-3450 5800);
DISPLAY INVISIBLE (-3450 5800);
FORCEPROP 1 LAST BODY_TYPE PLUMBING
J 2
(-2950 5650);
DISPLAY 0.702128 (-2950 5650);
PAINT GREEN (-2950 5650);
DISPLAY INVISIBLE (-2950 5650);
FORCEPROP 1 LAST HDL_TAP TRUE
J 2
(-3275 5575);
DISPLAY 0.702128 (-3275 5575);
PAINT GREEN (-3275 5575);
DISPLAY INVISIBLE (-3275 5575);
FORCEPROP 1 LAST PATH I437
J 2
(-2948 5700);
DISPLAY 0.872340 (-2948 5700);
PAINT GREEN (-2948 5700);
DISPLAY INVISIBLE (-2948 5700);
FORCEPROP 2 LAST ROOM RISER1
J 0
(-3450 5750);
DISPLAY 0.829787 (-3450 5750);
PAINT RED (-3450 5750);
DISPLAY INVISIBLE (-3450 5750);
FORCEADD TAP..6
R 2
(-2950 5600);
FORCEPROP 3 LASTPIN (-3000 5600) SIG_NAME GMI_CPU1_G0_CPU0_G2_TX_DN<14>
J 0
(-2990 5610);
DISPLAY 0.659574 (-2990 5610);
PAINT MONO (-2990 5610);
DISPLAY INVISIBLE (-2990 5610);
FORCEPROP 1 LASTPIN (-3000 5600) BN 14
J 2
(-2948 5608);
DISPLAY 0.489362 (-2948 5608);
PAINT MONO (-2948 5608);
FORCEPROP 2 LAST BOM_COST IO_SLOT
J 0
(-3450 5700);
DISPLAY 0.829787 (-3450 5700);
DISPLAY INVISIBLE (-3450 5700);
FORCEPROP 2 LAST CDS_LIB mstr_standard
J 0
(-2950 5600);
DISPLAY INVISIBLE (-2950 5600);
FORCEPROP 1 LAST BODY_TYPE PLUMBING
J 2
(-2950 5550);
DISPLAY 0.702128 (-2950 5550);
PAINT GREEN (-2950 5550);
DISPLAY INVISIBLE (-2950 5550);
FORCEPROP 1 LAST HDL_TAP TRUE
J 2
(-3275 5475);
DISPLAY 0.702128 (-3275 5475);
PAINT GREEN (-3275 5475);
DISPLAY INVISIBLE (-3275 5475);
FORCEPROP 1 LAST PATH I438
J 2
(-2948 5600);
DISPLAY 0.872340 (-2948 5600);
PAINT GREEN (-2948 5600);
DISPLAY INVISIBLE (-2948 5600);
FORCEPROP 2 LAST ROOM RISER1
J 0
(-3450 5650);
DISPLAY 0.829787 (-3450 5650);
PAINT RED (-3450 5650);
DISPLAY INVISIBLE (-3450 5650);
FORCEADD TAP..6
R 2
(-2950 5500);
FORCEPROP 3 LASTPIN (-3000 5500) SIG_NAME GMI_CPU1_G0_CPU0_G2_TX_DN<13>
J 0
(-2990 5510);
DISPLAY 0.659574 (-2990 5510);
PAINT MONO (-2990 5510);
DISPLAY INVISIBLE (-2990 5510);
FORCEPROP 1 LASTPIN (-3000 5500) BN 13
J 2
(-2948 5508);
DISPLAY 0.489362 (-2948 5508);
PAINT MONO (-2948 5508);
FORCEPROP 2 LAST BOM_COST IO_SLOT
J 0
(-3450 5600);
DISPLAY 0.829787 (-3450 5600);
DISPLAY INVISIBLE (-3450 5600);
FORCEPROP 2 LAST CDS_LIB standard
J 0
(-2950 5500);
DISPLAY INVISIBLE (-2950 5500);
FORCEPROP 1 LAST BODY_TYPE PLUMBING
J 2
(-2950 5450);
DISPLAY 0.702128 (-2950 5450);
PAINT GREEN (-2950 5450);
DISPLAY INVISIBLE (-2950 5450);
FORCEPROP 1 LAST HDL_TAP TRUE
J 2
(-3275 5375);
DISPLAY 0.702128 (-3275 5375);
PAINT GREEN (-3275 5375);
DISPLAY INVISIBLE (-3275 5375);
FORCEPROP 1 LAST PATH I439
J 2
(-2948 5500);
DISPLAY 0.872340 (-2948 5500);
PAINT GREEN (-2948 5500);
DISPLAY INVISIBLE (-2948 5500);
FORCEPROP 2 LAST ROOM RISER1
J 0
(-3450 5550);
DISPLAY 0.829787 (-3450 5550);
PAINT RED (-3450 5550);
DISPLAY INVISIBLE (-3450 5550);
FORCEADD TAP..6
R 2
(-2950 5400);
FORCEPROP 3 LASTPIN (-3000 5400) SIG_NAME GMI_CPU1_G0_CPU0_G2_TX_DN<12>
J 0
(-2990 5410);
DISPLAY 0.659574 (-2990 5410);
PAINT MONO (-2990 5410);
DISPLAY INVISIBLE (-2990 5410);
FORCEPROP 1 LASTPIN (-3000 5400) BN 12
J 2
(-2948 5408);
DISPLAY 0.489362 (-2948 5408);
PAINT MONO (-2948 5408);
FORCEPROP 2 LAST BOM_COST IO_SLOT
J 0
(-3450 5500);
DISPLAY 0.829787 (-3450 5500);
DISPLAY INVISIBLE (-3450 5500);
FORCEPROP 2 LAST CDS_LIB standard
J 0
(-2950 5400);
DISPLAY INVISIBLE (-2950 5400);
FORCEPROP 1 LAST BODY_TYPE PLUMBING
J 2
(-2950 5350);
DISPLAY 0.702128 (-2950 5350);
PAINT GREEN (-2950 5350);
DISPLAY INVISIBLE (-2950 5350);
FORCEPROP 1 LAST HDL_TAP TRUE
J 2
(-3275 5275);
DISPLAY 0.702128 (-3275 5275);
PAINT GREEN (-3275 5275);
DISPLAY INVISIBLE (-3275 5275);
FORCEPROP 1 LAST PATH I440
J 2
(-2948 5400);
DISPLAY 0.872340 (-2948 5400);
PAINT GREEN (-2948 5400);
DISPLAY INVISIBLE (-2948 5400);
FORCEPROP 2 LAST ROOM RISER1
J 0
(-3450 5450);
DISPLAY 0.829787 (-3450 5450);
PAINT RED (-3450 5450);
DISPLAY INVISIBLE (-3450 5450);
FORCEADD TAP..6
R 2
(-2950 5300);
FORCEPROP 3 LASTPIN (-3000 5300) SIG_NAME GMI_CPU1_G0_CPU0_G2_TX_DN<11>
J 0
(-2990 5310);
DISPLAY 0.659574 (-2990 5310);
PAINT MONO (-2990 5310);
DISPLAY INVISIBLE (-2990 5310);
FORCEPROP 1 LASTPIN (-3000 5300) BN 11
J 2
(-2948 5308);
DISPLAY 0.489362 (-2948 5308);
PAINT MONO (-2948 5308);
FORCEPROP 2 LAST BOM_COST IO_SLOT
J 0
(-3450 5400);
DISPLAY 0.829787 (-3450 5400);
DISPLAY INVISIBLE (-3450 5400);
FORCEPROP 2 LAST CDS_LIB standard
J 0
(-2950 5300);
DISPLAY INVISIBLE (-2950 5300);
FORCEPROP 1 LAST BODY_TYPE PLUMBING
J 2
(-2950 5250);
DISPLAY 0.702128 (-2950 5250);
PAINT GREEN (-2950 5250);
DISPLAY INVISIBLE (-2950 5250);
FORCEPROP 1 LAST HDL_TAP TRUE
J 2
(-3275 5175);
DISPLAY 0.702128 (-3275 5175);
PAINT GREEN (-3275 5175);
DISPLAY INVISIBLE (-3275 5175);
FORCEPROP 1 LAST PATH I441
J 2
(-2948 5300);
DISPLAY 0.872340 (-2948 5300);
PAINT GREEN (-2948 5300);
DISPLAY INVISIBLE (-2948 5300);
FORCEPROP 2 LAST ROOM RISER1
J 0
(-3450 5350);
DISPLAY 0.829787 (-3450 5350);
PAINT RED (-3450 5350);
DISPLAY INVISIBLE (-3450 5350);
FORCEADD TAP..6
R 2
(-2950 5200);
FORCEPROP 3 LASTPIN (-3000 5200) SIG_NAME GMI_CPU1_G0_CPU0_G2_TX_DN<10>
J 0
(-2990 5210);
DISPLAY 0.659574 (-2990 5210);
PAINT MONO (-2990 5210);
DISPLAY INVISIBLE (-2990 5210);
FORCEPROP 1 LASTPIN (-3000 5200) BN 10
J 2
(-2948 5208);
DISPLAY 0.489362 (-2948 5208);
PAINT MONO (-2948 5208);
FORCEPROP 2 LAST BOM_COST IO_SLOT
J 0
(-3450 5300);
DISPLAY 0.829787 (-3450 5300);
DISPLAY INVISIBLE (-3450 5300);
FORCEPROP 2 LAST CDS_LIB standard
J 0
(-2950 5200);
DISPLAY INVISIBLE (-2950 5200);
FORCEPROP 1 LAST BODY_TYPE PLUMBING
J 2
(-2950 5150);
DISPLAY 0.702128 (-2950 5150);
PAINT GREEN (-2950 5150);
DISPLAY INVISIBLE (-2950 5150);
FORCEPROP 1 LAST HDL_TAP TRUE
J 2
(-3275 5075);
DISPLAY 0.702128 (-3275 5075);
PAINT GREEN (-3275 5075);
DISPLAY INVISIBLE (-3275 5075);
FORCEPROP 1 LAST PATH I442
J 2
(-2948 5200);
DISPLAY 0.872340 (-2948 5200);
PAINT GREEN (-2948 5200);
DISPLAY INVISIBLE (-2948 5200);
FORCEPROP 2 LAST ROOM RISER1
J 0
(-3450 5250);
DISPLAY 0.829787 (-3450 5250);
PAINT RED (-3450 5250);
DISPLAY INVISIBLE (-3450 5250);
FORCEADD TAP..6
R 2
(-2950 5100);
FORCEPROP 3 LASTPIN (-3000 5100) SIG_NAME GMI_CPU1_G0_CPU0_G2_TX_DN<9>
J 0
(-2990 5110);
DISPLAY 0.659574 (-2990 5110);
PAINT MONO (-2990 5110);
DISPLAY INVISIBLE (-2990 5110);
FORCEPROP 1 LASTPIN (-3000 5100) BN 9
J 2
(-2948 5108);
DISPLAY 0.489362 (-2948 5108);
PAINT MONO (-2948 5108);
FORCEPROP 2 LAST BOM_COST IO_SLOT
J 0
(-3450 5200);
DISPLAY 0.829787 (-3450 5200);
DISPLAY INVISIBLE (-3450 5200);
FORCEPROP 2 LAST CDS_LIB standard
J 0
(-2950 5100);
DISPLAY INVISIBLE (-2950 5100);
FORCEPROP 1 LAST BODY_TYPE PLUMBING
J 2
(-2950 5050);
DISPLAY 0.702128 (-2950 5050);
PAINT GREEN (-2950 5050);
DISPLAY INVISIBLE (-2950 5050);
FORCEPROP 1 LAST HDL_TAP TRUE
J 2
(-3275 4975);
DISPLAY 0.702128 (-3275 4975);
PAINT GREEN (-3275 4975);
DISPLAY INVISIBLE (-3275 4975);
FORCEPROP 1 LAST PATH I443
J 2
(-2948 5100);
DISPLAY 0.872340 (-2948 5100);
PAINT GREEN (-2948 5100);
DISPLAY INVISIBLE (-2948 5100);
FORCEPROP 2 LAST ROOM RISER1
J 0
(-3450 5150);
DISPLAY 0.829787 (-3450 5150);
PAINT RED (-3450 5150);
DISPLAY INVISIBLE (-3450 5150);
FORCEADD TAP..6
R 2
(-2950 5000);
FORCEPROP 3 LASTPIN (-3000 5000) SIG_NAME GMI_CPU1_G0_CPU0_G2_TX_DN<8>
J 0
(-2990 5010);
DISPLAY 0.659574 (-2990 5010);
PAINT MONO (-2990 5010);
DISPLAY INVISIBLE (-2990 5010);
FORCEPROP 1 LASTPIN (-3000 5000) BN 8
J 2
(-2948 5008);
DISPLAY 0.489362 (-2948 5008);
PAINT MONO (-2948 5008);
FORCEPROP 2 LAST BOM_COST IO_SLOT
J 0
(-3450 5100);
DISPLAY 0.829787 (-3450 5100);
DISPLAY INVISIBLE (-3450 5100);
FORCEPROP 2 LAST CDS_LIB standard
J 0
(-2950 5000);
DISPLAY INVISIBLE (-2950 5000);
FORCEPROP 1 LAST BODY_TYPE PLUMBING
J 2
(-2950 4950);
DISPLAY 0.702128 (-2950 4950);
PAINT GREEN (-2950 4950);
DISPLAY INVISIBLE (-2950 4950);
FORCEPROP 1 LAST HDL_TAP TRUE
J 2
(-3275 4875);
DISPLAY 0.702128 (-3275 4875);
PAINT GREEN (-3275 4875);
DISPLAY INVISIBLE (-3275 4875);
FORCEPROP 1 LAST PATH I444
J 2
(-2948 5000);
DISPLAY 0.872340 (-2948 5000);
PAINT GREEN (-2948 5000);
DISPLAY INVISIBLE (-2948 5000);
FORCEPROP 2 LAST ROOM RISER1
J 0
(-3450 5050);
DISPLAY 0.829787 (-3450 5050);
PAINT RED (-3450 5050);
DISPLAY INVISIBLE (-3450 5050);
FORCEADD TAP..6
R 2
(-2950 4900);
FORCEPROP 3 LASTPIN (-3000 4900) SIG_NAME GMI_CPU1_G0_CPU0_G2_TX_DN<7>
J 0
(-2990 4910);
DISPLAY 0.659574 (-2990 4910);
PAINT MONO (-2990 4910);
DISPLAY INVISIBLE (-2990 4910);
FORCEPROP 1 LASTPIN (-3000 4900) BN 7
J 2
(-2948 4908);
DISPLAY 0.489362 (-2948 4908);
PAINT MONO (-2948 4908);
FORCEPROP 2 LAST BOM_COST IO_SLOT
J 0
(-3450 5000);
DISPLAY 0.829787 (-3450 5000);
DISPLAY INVISIBLE (-3450 5000);
FORCEPROP 2 LAST CDS_LIB standard
J 0
(-2950 4900);
DISPLAY INVISIBLE (-2950 4900);
FORCEPROP 1 LAST BODY_TYPE PLUMBING
J 2
(-2950 4850);
DISPLAY 0.702128 (-2950 4850);
PAINT GREEN (-2950 4850);
DISPLAY INVISIBLE (-2950 4850);
FORCEPROP 1 LAST HDL_TAP TRUE
J 2
(-3275 4775);
DISPLAY 0.702128 (-3275 4775);
PAINT GREEN (-3275 4775);
DISPLAY INVISIBLE (-3275 4775);
FORCEPROP 1 LAST PATH I445
J 2
(-2948 4900);
DISPLAY 0.872340 (-2948 4900);
PAINT GREEN (-2948 4900);
DISPLAY INVISIBLE (-2948 4900);
FORCEPROP 2 LAST ROOM RISER1
J 0
(-3450 4950);
DISPLAY 0.829787 (-3450 4950);
PAINT RED (-3450 4950);
DISPLAY INVISIBLE (-3450 4950);
FORCEADD TAP..6
R 2
(-2950 4700);
FORCEPROP 3 LASTPIN (-3000 4700) SIG_NAME GMI_CPU1_G0_CPU0_G2_TX_DN<5>
J 0
(-2990 4710);
DISPLAY 0.659574 (-2990 4710);
PAINT MONO (-2990 4710);
DISPLAY INVISIBLE (-2990 4710);
FORCEPROP 1 LASTPIN (-3000 4700) BN 5
J 2
(-2948 4708);
DISPLAY 0.489362 (-2948 4708);
PAINT MONO (-2948 4708);
FORCEPROP 2 LAST BOM_COST IO_SLOT
J 0
(-3450 4800);
DISPLAY 0.829787 (-3450 4800);
DISPLAY INVISIBLE (-3450 4800);
FORCEPROP 2 LAST CDS_LIB standard
J 0
(-2950 4700);
DISPLAY INVISIBLE (-2950 4700);
FORCEPROP 1 LAST BODY_TYPE PLUMBING
J 2
(-2950 4650);
DISPLAY 0.702128 (-2950 4650);
PAINT GREEN (-2950 4650);
DISPLAY INVISIBLE (-2950 4650);
FORCEPROP 1 LAST HDL_TAP TRUE
J 2
(-3275 4575);
DISPLAY 0.702128 (-3275 4575);
PAINT GREEN (-3275 4575);
DISPLAY INVISIBLE (-3275 4575);
FORCEPROP 1 LAST PATH I446
J 2
(-2948 4700);
DISPLAY 0.872340 (-2948 4700);
PAINT GREEN (-2948 4700);
DISPLAY INVISIBLE (-2948 4700);
FORCEPROP 2 LAST ROOM RISER1
J 0
(-3450 4750);
DISPLAY 0.829787 (-3450 4750);
PAINT RED (-3450 4750);
DISPLAY INVISIBLE (-3450 4750);
FORCEADD TAP..6
R 2
(-2950 4800);
FORCEPROP 3 LASTPIN (-3000 4800) SIG_NAME GMI_CPU1_G0_CPU0_G2_TX_DN<6>
J 0
(-2990 4810);
DISPLAY 0.659574 (-2990 4810);
PAINT MONO (-2990 4810);
DISPLAY INVISIBLE (-2990 4810);
FORCEPROP 1 LASTPIN (-3000 4800) BN 6
J 2
(-2948 4808);
DISPLAY 0.489362 (-2948 4808);
PAINT MONO (-2948 4808);
FORCEPROP 2 LAST BOM_COST IO_SLOT
J 0
(-3450 4900);
DISPLAY 0.829787 (-3450 4900);
DISPLAY INVISIBLE (-3450 4900);
FORCEPROP 2 LAST CDS_LIB standard
J 0
(-2950 4800);
DISPLAY INVISIBLE (-2950 4800);
FORCEPROP 1 LAST BODY_TYPE PLUMBING
J 2
(-2950 4750);
DISPLAY 0.702128 (-2950 4750);
PAINT GREEN (-2950 4750);
DISPLAY INVISIBLE (-2950 4750);
FORCEPROP 1 LAST HDL_TAP TRUE
J 2
(-3275 4675);
DISPLAY 0.702128 (-3275 4675);
PAINT GREEN (-3275 4675);
DISPLAY INVISIBLE (-3275 4675);
FORCEPROP 1 LAST PATH I447
J 2
(-2948 4800);
DISPLAY 0.872340 (-2948 4800);
PAINT GREEN (-2948 4800);
DISPLAY INVISIBLE (-2948 4800);
FORCEPROP 2 LAST ROOM RISER1
J 0
(-3450 4850);
DISPLAY 0.829787 (-3450 4850);
PAINT RED (-3450 4850);
DISPLAY INVISIBLE (-3450 4850);
FORCEADD TAP..6
R 2
(-2950 4600);
FORCEPROP 3 LASTPIN (-3000 4600) SIG_NAME GMI_CPU1_G0_CPU0_G2_TX_DN<4>
J 0
(-2990 4610);
DISPLAY 0.659574 (-2990 4610);
PAINT MONO (-2990 4610);
DISPLAY INVISIBLE (-2990 4610);
FORCEPROP 1 LASTPIN (-3000 4600) BN 4
J 2
(-2948 4608);
DISPLAY 0.489362 (-2948 4608);
PAINT MONO (-2948 4608);
FORCEPROP 2 LAST BOM_COST IO_SLOT
J 0
(-3450 4700);
DISPLAY 0.829787 (-3450 4700);
DISPLAY INVISIBLE (-3450 4700);
FORCEPROP 2 LAST CDS_LIB standard
J 0
(-2950 4600);
DISPLAY INVISIBLE (-2950 4600);
FORCEPROP 1 LAST BODY_TYPE PLUMBING
J 2
(-2950 4550);
DISPLAY 0.702128 (-2950 4550);
PAINT GREEN (-2950 4550);
DISPLAY INVISIBLE (-2950 4550);
FORCEPROP 1 LAST HDL_TAP TRUE
J 2
(-3275 4475);
DISPLAY 0.702128 (-3275 4475);
PAINT GREEN (-3275 4475);
DISPLAY INVISIBLE (-3275 4475);
FORCEPROP 1 LAST PATH I448
J 2
(-2948 4600);
DISPLAY 0.872340 (-2948 4600);
PAINT GREEN (-2948 4600);
DISPLAY INVISIBLE (-2948 4600);
FORCEPROP 2 LAST ROOM RISER1
J 0
(-3450 4650);
DISPLAY 0.829787 (-3450 4650);
PAINT RED (-3450 4650);
DISPLAY INVISIBLE (-3450 4650);
FORCEADD TAP..6
R 2
(-2950 4500);
FORCEPROP 3 LASTPIN (-3000 4500) SIG_NAME GMI_CPU1_G0_CPU0_G2_TX_DN<3>
J 0
(-2990 4510);
DISPLAY 0.659574 (-2990 4510);
PAINT MONO (-2990 4510);
DISPLAY INVISIBLE (-2990 4510);
FORCEPROP 1 LASTPIN (-3000 4500) BN 3
J 2
(-2948 4508);
DISPLAY 0.489362 (-2948 4508);
PAINT MONO (-2948 4508);
FORCEPROP 2 LAST BOM_COST IO_SLOT
J 0
(-3450 4600);
DISPLAY 0.829787 (-3450 4600);
DISPLAY INVISIBLE (-3450 4600);
FORCEPROP 2 LAST CDS_LIB standard
J 0
(-2950 4500);
DISPLAY INVISIBLE (-2950 4500);
FORCEPROP 1 LAST BODY_TYPE PLUMBING
J 2
(-2950 4450);
DISPLAY 0.702128 (-2950 4450);
PAINT GREEN (-2950 4450);
DISPLAY INVISIBLE (-2950 4450);
FORCEPROP 1 LAST HDL_TAP TRUE
J 2
(-3275 4375);
DISPLAY 0.702128 (-3275 4375);
PAINT GREEN (-3275 4375);
DISPLAY INVISIBLE (-3275 4375);
FORCEPROP 1 LAST PATH I449
J 2
(-2948 4500);
DISPLAY 0.872340 (-2948 4500);
PAINT GREEN (-2948 4500);
DISPLAY INVISIBLE (-2948 4500);
FORCEPROP 2 LAST ROOM RISER1
J 0
(-3450 4550);
DISPLAY 0.829787 (-3450 4550);
PAINT RED (-3450 4550);
DISPLAY INVISIBLE (-3450 4550);
FORCEADD TAP..6
R 2
(-2950 4300);
FORCEPROP 3 LASTPIN (-3000 4300) SIG_NAME GMI_CPU1_G0_CPU0_G2_TX_DN<1>
J 0
(-2990 4310);
DISPLAY 0.659574 (-2990 4310);
PAINT MONO (-2990 4310);
DISPLAY INVISIBLE (-2990 4310);
FORCEPROP 1 LASTPIN (-3000 4300) BN 1
J 2
(-2948 4308);
DISPLAY 0.489362 (-2948 4308);
PAINT MONO (-2948 4308);
FORCEPROP 2 LAST CDS_LIB standard
J 0
(-2950 4300);
DISPLAY INVISIBLE (-2950 4300);
FORCEPROP 2 LAST BOM_COST IO_SLOT
J 0
(-3450 4400);
DISPLAY 0.829787 (-3450 4400);
DISPLAY INVISIBLE (-3450 4400);
FORCEPROP 1 LAST BODY_TYPE PLUMBING
J 2
(-2950 4250);
DISPLAY 0.702128 (-2950 4250);
PAINT GREEN (-2950 4250);
DISPLAY INVISIBLE (-2950 4250);
FORCEPROP 1 LAST HDL_TAP TRUE
J 2
(-3275 4175);
DISPLAY 0.702128 (-3275 4175);
PAINT GREEN (-3275 4175);
DISPLAY INVISIBLE (-3275 4175);
FORCEPROP 1 LAST PATH I450
J 2
(-2948 4300);
DISPLAY 0.872340 (-2948 4300);
PAINT GREEN (-2948 4300);
DISPLAY INVISIBLE (-2948 4300);
FORCEPROP 2 LAST ROOM RISER1
J 0
(-3450 4350);
DISPLAY 0.829787 (-3450 4350);
PAINT RED (-3450 4350);
DISPLAY INVISIBLE (-3450 4350);
FORCEADD TAP..6
R 2
(-2950 4400);
FORCEPROP 3 LASTPIN (-3000 4400) SIG_NAME GMI_CPU1_G0_CPU0_G2_TX_DN<2>
J 0
(-2990 4410);
DISPLAY 0.659574 (-2990 4410);
PAINT MONO (-2990 4410);
DISPLAY INVISIBLE (-2990 4410);
FORCEPROP 1 LASTPIN (-3000 4400) BN 2
J 2
(-2948 4408);
DISPLAY 0.489362 (-2948 4408);
PAINT MONO (-2948 4408);
FORCEPROP 2 LAST BOM_COST IO_SLOT
J 0
(-3450 4500);
DISPLAY 0.829787 (-3450 4500);
DISPLAY INVISIBLE (-3450 4500);
FORCEPROP 2 LAST CDS_LIB standard
J 0
(-2950 4400);
DISPLAY INVISIBLE (-2950 4400);
FORCEPROP 1 LAST BODY_TYPE PLUMBING
J 2
(-2950 4350);
DISPLAY 0.702128 (-2950 4350);
PAINT GREEN (-2950 4350);
DISPLAY INVISIBLE (-2950 4350);
FORCEPROP 1 LAST HDL_TAP TRUE
J 2
(-3275 4275);
DISPLAY 0.702128 (-3275 4275);
PAINT GREEN (-3275 4275);
DISPLAY INVISIBLE (-3275 4275);
FORCEPROP 1 LAST PATH I451
J 2
(-2948 4400);
DISPLAY 0.872340 (-2948 4400);
PAINT GREEN (-2948 4400);
DISPLAY INVISIBLE (-2948 4400);
FORCEPROP 2 LAST ROOM RISER1
J 0
(-3450 4450);
DISPLAY 0.829787 (-3450 4450);
PAINT RED (-3450 4450);
DISPLAY INVISIBLE (-3450 4450);
FORCEADD TAP..6
R 2
(-2950 4200);
FORCEPROP 3 LASTPIN (-3000 4200) SIG_NAME GMI_CPU1_G0_CPU0_G2_TX_DN<0>
J 0
(-2990 4210);
DISPLAY 0.659574 (-2990 4210);
PAINT MONO (-2990 4210);
DISPLAY INVISIBLE (-2990 4210);
FORCEPROP 1 LASTPIN (-3000 4200) BN 0
J 2
(-2948 4208);
DISPLAY 0.489362 (-2948 4208);
PAINT MONO (-2948 4208);
FORCEPROP 2 LAST BOM_COST IO_SLOT
J 0
(-3450 4300);
DISPLAY 0.829787 (-3450 4300);
DISPLAY INVISIBLE (-3450 4300);
FORCEPROP 2 LAST CDS_LIB standard
J 0
(-2950 4200);
DISPLAY INVISIBLE (-2950 4200);
FORCEPROP 1 LAST BODY_TYPE PLUMBING
J 2
(-2950 4150);
DISPLAY 0.702128 (-2950 4150);
PAINT GREEN (-2950 4150);
DISPLAY INVISIBLE (-2950 4150);
FORCEPROP 1 LAST HDL_TAP TRUE
J 2
(-3275 4075);
DISPLAY 0.702128 (-3275 4075);
PAINT GREEN (-3275 4075);
DISPLAY INVISIBLE (-3275 4075);
FORCEPROP 1 LAST PATH I452
J 2
(-2948 4200);
DISPLAY 0.872340 (-2948 4200);
PAINT GREEN (-2948 4200);
DISPLAY INVISIBLE (-2948 4200);
FORCEPROP 2 LAST ROOM RISER1
J 0
(-3450 4250);
DISPLAY 0.829787 (-3450 4250);
PAINT RED (-3450 4250);
DISPLAY INVISIBLE (-3450 4250);
FORCEADD TAP..6
(-6675 5700);
FORCEPROP 3 LASTPIN (-6625 5700) SIG_NAME GMI_CPU0_G2_CPU1_G0_TX_DN<15>
J 0
(-6615 5710);
DISPLAY 0.659574 (-6615 5710);
PAINT MONO (-6615 5710);
DISPLAY INVISIBLE (-6615 5710);
FORCEPROP 1 LASTPIN (-6625 5700) BN 15
J 0
(-6677 5708);
DISPLAY 0.489362 (-6677 5708);
PAINT MONO (-6677 5708);
FORCEPROP 2 LAST CDS_LIB mstr_standard
J 0
(-6675 5700);
DISPLAY INVISIBLE (-6675 5700);
FORCEPROP 1 LAST BODY_TYPE PLUMBING
J 0
(-6675 5650);
DISPLAY 0.574468 (-6675 5650);
PAINT GREEN (-6675 5650);
DISPLAY INVISIBLE (-6675 5650);
FORCEPROP 1 LAST HDL_TAP TRUE
J 0
(-6350 5575);
DISPLAY 0.574468 (-6350 5575);
PAINT GREEN (-6350 5575);
DISPLAY INVISIBLE (-6350 5575);
FORCEPROP 1 LAST PATH I453
J 0
(-6677 5700);
DISPLAY 0.872340 (-6677 5700);
PAINT GREEN (-6677 5700);
DISPLAY INVISIBLE (-6677 5700);
FORCEADD TAP..6
(-6675 5600);
FORCEPROP 3 LASTPIN (-6625 5600) SIG_NAME GMI_CPU0_G2_CPU1_G0_TX_DN<14>
J 0
(-6615 5610);
DISPLAY 0.659574 (-6615 5610);
PAINT MONO (-6615 5610);
DISPLAY INVISIBLE (-6615 5610);
FORCEPROP 1 LASTPIN (-6625 5600) BN 14
J 0
(-6677 5608);
DISPLAY 0.489362 (-6677 5608);
PAINT MONO (-6677 5608);
FORCEPROP 2 LAST CDS_LIB mstr_standard
J 0
(-6675 5600);
DISPLAY INVISIBLE (-6675 5600);
FORCEPROP 1 LAST BODY_TYPE PLUMBING
J 0
(-6675 5550);
DISPLAY 0.574468 (-6675 5550);
PAINT GREEN (-6675 5550);
DISPLAY INVISIBLE (-6675 5550);
FORCEPROP 1 LAST HDL_TAP TRUE
J 0
(-6350 5475);
DISPLAY 0.574468 (-6350 5475);
PAINT GREEN (-6350 5475);
DISPLAY INVISIBLE (-6350 5475);
FORCEPROP 1 LAST PATH I454
J 0
(-6677 5600);
DISPLAY 0.872340 (-6677 5600);
PAINT GREEN (-6677 5600);
DISPLAY INVISIBLE (-6677 5600);
FORCEADD TAP..6
(-6675 5500);
FORCEPROP 3 LASTPIN (-6625 5500) SIG_NAME GMI_CPU0_G2_CPU1_G0_TX_DN<13>
J 0
(-6615 5510);
DISPLAY 0.659574 (-6615 5510);
PAINT MONO (-6615 5510);
DISPLAY INVISIBLE (-6615 5510);
FORCEPROP 1 LASTPIN (-6625 5500) BN 13
J 0
(-6677 5508);
DISPLAY 0.489362 (-6677 5508);
PAINT MONO (-6677 5508);
FORCEPROP 2 LAST CDS_LIB standard
J 0
(-6675 5500);
DISPLAY INVISIBLE (-6675 5500);
FORCEPROP 1 LAST BODY_TYPE PLUMBING
J 0
(-6675 5450);
DISPLAY 0.574468 (-6675 5450);
PAINT GREEN (-6675 5450);
DISPLAY INVISIBLE (-6675 5450);
FORCEPROP 1 LAST HDL_TAP TRUE
J 0
(-6350 5375);
DISPLAY 0.574468 (-6350 5375);
PAINT GREEN (-6350 5375);
DISPLAY INVISIBLE (-6350 5375);
FORCEPROP 1 LAST PATH I455
J 0
(-6677 5500);
DISPLAY 0.872340 (-6677 5500);
PAINT GREEN (-6677 5500);
DISPLAY INVISIBLE (-6677 5500);
FORCEADD TAP..6
(-6675 5400);
FORCEPROP 3 LASTPIN (-6625 5400) SIG_NAME GMI_CPU0_G2_CPU1_G0_TX_DN<12>
J 0
(-6615 5410);
DISPLAY 0.659574 (-6615 5410);
PAINT MONO (-6615 5410);
DISPLAY INVISIBLE (-6615 5410);
FORCEPROP 1 LASTPIN (-6625 5400) BN 12
J 0
(-6677 5408);
DISPLAY 0.489362 (-6677 5408);
PAINT MONO (-6677 5408);
FORCEPROP 2 LAST CDS_LIB standard
J 0
(-6675 5400);
DISPLAY INVISIBLE (-6675 5400);
FORCEPROP 1 LAST BODY_TYPE PLUMBING
J 0
(-6675 5350);
DISPLAY 0.574468 (-6675 5350);
PAINT GREEN (-6675 5350);
DISPLAY INVISIBLE (-6675 5350);
FORCEPROP 1 LAST HDL_TAP TRUE
J 0
(-6350 5275);
DISPLAY 0.574468 (-6350 5275);
PAINT GREEN (-6350 5275);
DISPLAY INVISIBLE (-6350 5275);
FORCEPROP 1 LAST PATH I456
J 0
(-6677 5400);
DISPLAY 0.872340 (-6677 5400);
PAINT GREEN (-6677 5400);
DISPLAY INVISIBLE (-6677 5400);
FORCEADD TAP..6
(-6675 5200);
FORCEPROP 3 LASTPIN (-6625 5200) SIG_NAME GMI_CPU0_G2_CPU1_G0_TX_DN<10>
J 0
(-6615 5210);
DISPLAY 0.659574 (-6615 5210);
PAINT MONO (-6615 5210);
DISPLAY INVISIBLE (-6615 5210);
FORCEPROP 1 LASTPIN (-6625 5200) BN 10
J 0
(-6677 5208);
DISPLAY 0.489362 (-6677 5208);
PAINT MONO (-6677 5208);
FORCEPROP 2 LAST CDS_LIB standard
J 0
(-6675 5200);
DISPLAY INVISIBLE (-6675 5200);
FORCEPROP 1 LAST BODY_TYPE PLUMBING
J 0
(-6675 5150);
DISPLAY 0.574468 (-6675 5150);
PAINT GREEN (-6675 5150);
DISPLAY INVISIBLE (-6675 5150);
FORCEPROP 1 LAST HDL_TAP TRUE
J 0
(-6350 5075);
DISPLAY 0.574468 (-6350 5075);
PAINT GREEN (-6350 5075);
DISPLAY INVISIBLE (-6350 5075);
FORCEPROP 1 LAST PATH I457
J 0
(-6677 5200);
DISPLAY 0.872340 (-6677 5200);
PAINT GREEN (-6677 5200);
DISPLAY INVISIBLE (-6677 5200);
FORCEADD TAP..6
(-6675 5300);
FORCEPROP 3 LASTPIN (-6625 5300) SIG_NAME GMI_CPU0_G2_CPU1_G0_TX_DN<11>
J 0
(-6615 5310);
DISPLAY 0.659574 (-6615 5310);
PAINT MONO (-6615 5310);
DISPLAY INVISIBLE (-6615 5310);
FORCEPROP 1 LASTPIN (-6625 5300) BN 11
J 0
(-6677 5308);
DISPLAY 0.489362 (-6677 5308);
PAINT MONO (-6677 5308);
FORCEPROP 2 LAST CDS_LIB standard
J 0
(-6675 5300);
DISPLAY INVISIBLE (-6675 5300);
FORCEPROP 1 LAST BODY_TYPE PLUMBING
J 0
(-6675 5250);
DISPLAY 0.574468 (-6675 5250);
PAINT GREEN (-6675 5250);
DISPLAY INVISIBLE (-6675 5250);
FORCEPROP 1 LAST HDL_TAP TRUE
J 0
(-6350 5175);
DISPLAY 0.574468 (-6350 5175);
PAINT GREEN (-6350 5175);
DISPLAY INVISIBLE (-6350 5175);
FORCEPROP 1 LAST PATH I458
J 0
(-6677 5300);
DISPLAY 0.872340 (-6677 5300);
PAINT GREEN (-6677 5300);
DISPLAY INVISIBLE (-6677 5300);
FORCEADD TAP..6
(-6675 5100);
FORCEPROP 3 LASTPIN (-6625 5100) SIG_NAME GMI_CPU0_G2_CPU1_G0_TX_DN<9>
J 0
(-6615 5110);
DISPLAY 0.659574 (-6615 5110);
PAINT MONO (-6615 5110);
DISPLAY INVISIBLE (-6615 5110);
FORCEPROP 1 LASTPIN (-6625 5100) BN 9
J 0
(-6677 5108);
DISPLAY 0.489362 (-6677 5108);
PAINT MONO (-6677 5108);
FORCEPROP 2 LAST CDS_LIB standard
J 0
(-6675 5100);
DISPLAY INVISIBLE (-6675 5100);
FORCEPROP 1 LAST BODY_TYPE PLUMBING
J 0
(-6675 5050);
DISPLAY 0.574468 (-6675 5050);
PAINT GREEN (-6675 5050);
DISPLAY INVISIBLE (-6675 5050);
FORCEPROP 1 LAST HDL_TAP TRUE
J 0
(-6350 4975);
DISPLAY 0.574468 (-6350 4975);
PAINT GREEN (-6350 4975);
DISPLAY INVISIBLE (-6350 4975);
FORCEPROP 1 LAST PATH I459
J 0
(-6677 5100);
DISPLAY 0.872340 (-6677 5100);
PAINT GREEN (-6677 5100);
DISPLAY INVISIBLE (-6677 5100);
FORCEADD TAP..6
(-6675 5000);
FORCEPROP 3 LASTPIN (-6625 5000) SIG_NAME GMI_CPU0_G2_CPU1_G0_TX_DN<8>
J 0
(-6615 5010);
DISPLAY 0.659574 (-6615 5010);
PAINT MONO (-6615 5010);
DISPLAY INVISIBLE (-6615 5010);
FORCEPROP 1 LASTPIN (-6625 5000) BN 8
J 0
(-6677 5008);
DISPLAY 0.489362 (-6677 5008);
PAINT MONO (-6677 5008);
FORCEPROP 2 LAST CDS_LIB standard
J 0
(-6675 5000);
DISPLAY INVISIBLE (-6675 5000);
FORCEPROP 1 LAST BODY_TYPE PLUMBING
J 0
(-6675 4950);
DISPLAY 0.574468 (-6675 4950);
PAINT GREEN (-6675 4950);
DISPLAY INVISIBLE (-6675 4950);
FORCEPROP 1 LAST HDL_TAP TRUE
J 0
(-6350 4875);
DISPLAY 0.574468 (-6350 4875);
PAINT GREEN (-6350 4875);
DISPLAY INVISIBLE (-6350 4875);
FORCEPROP 1 LAST PATH I460
J 0
(-6677 5000);
DISPLAY 0.872340 (-6677 5000);
PAINT GREEN (-6677 5000);
DISPLAY INVISIBLE (-6677 5000);
FORCEADD TAP..6
(-6675 4900);
FORCEPROP 3 LASTPIN (-6625 4900) SIG_NAME GMI_CPU0_G2_CPU1_G0_TX_DN<7>
J 0
(-6615 4910);
DISPLAY 0.659574 (-6615 4910);
PAINT MONO (-6615 4910);
DISPLAY INVISIBLE (-6615 4910);
FORCEPROP 1 LASTPIN (-6625 4900) BN 7
J 0
(-6677 4908);
DISPLAY 0.489362 (-6677 4908);
PAINT MONO (-6677 4908);
FORCEPROP 2 LAST CDS_LIB standard
J 0
(-6675 4900);
DISPLAY INVISIBLE (-6675 4900);
FORCEPROP 1 LAST BODY_TYPE PLUMBING
J 0
(-6675 4850);
DISPLAY 0.574468 (-6675 4850);
PAINT GREEN (-6675 4850);
DISPLAY INVISIBLE (-6675 4850);
FORCEPROP 1 LAST HDL_TAP TRUE
J 0
(-6350 4775);
DISPLAY 0.574468 (-6350 4775);
PAINT GREEN (-6350 4775);
DISPLAY INVISIBLE (-6350 4775);
FORCEPROP 1 LAST PATH I461
J 0
(-6677 4900);
DISPLAY 0.872340 (-6677 4900);
PAINT GREEN (-6677 4900);
DISPLAY INVISIBLE (-6677 4900);
FORCEADD TAP..6
(-6675 4800);
FORCEPROP 3 LASTPIN (-6625 4800) SIG_NAME GMI_CPU0_G2_CPU1_G0_TX_DN<6>
J 0
(-6615 4810);
DISPLAY 0.659574 (-6615 4810);
PAINT MONO (-6615 4810);
DISPLAY INVISIBLE (-6615 4810);
FORCEPROP 1 LASTPIN (-6625 4800) BN 6
J 0
(-6677 4808);
DISPLAY 0.489362 (-6677 4808);
PAINT MONO (-6677 4808);
FORCEPROP 2 LAST CDS_LIB standard
J 0
(-6675 4800);
DISPLAY INVISIBLE (-6675 4800);
FORCEPROP 1 LAST BODY_TYPE PLUMBING
J 0
(-6675 4750);
DISPLAY 0.574468 (-6675 4750);
PAINT GREEN (-6675 4750);
DISPLAY INVISIBLE (-6675 4750);
FORCEPROP 1 LAST HDL_TAP TRUE
J 0
(-6350 4675);
DISPLAY 0.574468 (-6350 4675);
PAINT GREEN (-6350 4675);
DISPLAY INVISIBLE (-6350 4675);
FORCEPROP 1 LAST PATH I462
J 0
(-6677 4800);
DISPLAY 0.872340 (-6677 4800);
PAINT GREEN (-6677 4800);
DISPLAY INVISIBLE (-6677 4800);
FORCEADD TAP..6
(-6675 4700);
FORCEPROP 3 LASTPIN (-6625 4700) SIG_NAME GMI_CPU0_G2_CPU1_G0_TX_DN<5>
J 0
(-6615 4710);
DISPLAY 0.659574 (-6615 4710);
PAINT MONO (-6615 4710);
DISPLAY INVISIBLE (-6615 4710);
FORCEPROP 1 LASTPIN (-6625 4700) BN 5
J 0
(-6677 4708);
DISPLAY 0.489362 (-6677 4708);
PAINT MONO (-6677 4708);
FORCEPROP 2 LAST CDS_LIB standard
J 0
(-6675 4700);
DISPLAY INVISIBLE (-6675 4700);
FORCEPROP 1 LAST BODY_TYPE PLUMBING
J 0
(-6675 4650);
DISPLAY 0.574468 (-6675 4650);
PAINT GREEN (-6675 4650);
DISPLAY INVISIBLE (-6675 4650);
FORCEPROP 1 LAST HDL_TAP TRUE
J 0
(-6350 4575);
DISPLAY 0.574468 (-6350 4575);
PAINT GREEN (-6350 4575);
DISPLAY INVISIBLE (-6350 4575);
FORCEPROP 1 LAST PATH I463
J 0
(-6677 4700);
DISPLAY 0.872340 (-6677 4700);
PAINT GREEN (-6677 4700);
DISPLAY INVISIBLE (-6677 4700);
FORCEADD TAP..6
(-6675 4600);
FORCEPROP 3 LASTPIN (-6625 4600) SIG_NAME GMI_CPU0_G2_CPU1_G0_TX_DN<4>
J 0
(-6615 4610);
DISPLAY 0.659574 (-6615 4610);
PAINT MONO (-6615 4610);
DISPLAY INVISIBLE (-6615 4610);
FORCEPROP 1 LASTPIN (-6625 4600) BN 4
J 0
(-6677 4608);
DISPLAY 0.489362 (-6677 4608);
PAINT MONO (-6677 4608);
FORCEPROP 2 LAST CDS_LIB standard
J 0
(-6675 4600);
DISPLAY INVISIBLE (-6675 4600);
FORCEPROP 1 LAST BODY_TYPE PLUMBING
J 0
(-6675 4550);
DISPLAY 0.574468 (-6675 4550);
PAINT GREEN (-6675 4550);
DISPLAY INVISIBLE (-6675 4550);
FORCEPROP 1 LAST HDL_TAP TRUE
J 0
(-6350 4475);
DISPLAY 0.574468 (-6350 4475);
PAINT GREEN (-6350 4475);
DISPLAY INVISIBLE (-6350 4475);
FORCEPROP 1 LAST PATH I464
J 0
(-6677 4600);
DISPLAY 0.872340 (-6677 4600);
PAINT GREEN (-6677 4600);
DISPLAY INVISIBLE (-6677 4600);
FORCEADD TAP..6
(-6675 4500);
FORCEPROP 3 LASTPIN (-6625 4500) SIG_NAME GMI_CPU0_G2_CPU1_G0_TX_DN<3>
J 0
(-6615 4510);
DISPLAY 0.659574 (-6615 4510);
PAINT MONO (-6615 4510);
DISPLAY INVISIBLE (-6615 4510);
FORCEPROP 1 LASTPIN (-6625 4500) BN 3
J 0
(-6677 4508);
DISPLAY 0.489362 (-6677 4508);
PAINT MONO (-6677 4508);
FORCEPROP 2 LAST CDS_LIB standard
J 0
(-6675 4500);
DISPLAY INVISIBLE (-6675 4500);
FORCEPROP 1 LAST BODY_TYPE PLUMBING
J 0
(-6675 4450);
DISPLAY 0.574468 (-6675 4450);
PAINT GREEN (-6675 4450);
DISPLAY INVISIBLE (-6675 4450);
FORCEPROP 1 LAST HDL_TAP TRUE
J 0
(-6350 4375);
DISPLAY 0.574468 (-6350 4375);
PAINT GREEN (-6350 4375);
DISPLAY INVISIBLE (-6350 4375);
FORCEPROP 1 LAST PATH I465
J 0
(-6677 4500);
DISPLAY 0.872340 (-6677 4500);
PAINT GREEN (-6677 4500);
DISPLAY INVISIBLE (-6677 4500);
FORCEADD TAP..6
(-6675 4400);
FORCEPROP 3 LASTPIN (-6625 4400) SIG_NAME GMI_CPU0_G2_CPU1_G0_TX_DN<2>
J 0
(-6615 4410);
DISPLAY 0.659574 (-6615 4410);
PAINT MONO (-6615 4410);
DISPLAY INVISIBLE (-6615 4410);
FORCEPROP 1 LASTPIN (-6625 4400) BN 2
J 0
(-6677 4408);
DISPLAY 0.489362 (-6677 4408);
PAINT MONO (-6677 4408);
FORCEPROP 2 LAST CDS_LIB standard
J 0
(-6675 4400);
DISPLAY INVISIBLE (-6675 4400);
FORCEPROP 1 LAST BODY_TYPE PLUMBING
J 0
(-6675 4350);
DISPLAY 0.574468 (-6675 4350);
PAINT GREEN (-6675 4350);
DISPLAY INVISIBLE (-6675 4350);
FORCEPROP 1 LAST HDL_TAP TRUE
J 0
(-6350 4275);
DISPLAY 0.574468 (-6350 4275);
PAINT GREEN (-6350 4275);
DISPLAY INVISIBLE (-6350 4275);
FORCEPROP 1 LAST PATH I466
J 0
(-6677 4400);
DISPLAY 0.872340 (-6677 4400);
PAINT GREEN (-6677 4400);
DISPLAY INVISIBLE (-6677 4400);
FORCEADD TAP..6
(-6675 4200);
FORCEPROP 3 LASTPIN (-6625 4200) SIG_NAME GMI_CPU0_G2_CPU1_G0_TX_DN<0>
J 0
(-6615 4210);
DISPLAY 0.659574 (-6615 4210);
PAINT MONO (-6615 4210);
DISPLAY INVISIBLE (-6615 4210);
FORCEPROP 1 LASTPIN (-6625 4200) BN 0
J 0
(-6677 4208);
DISPLAY 0.489362 (-6677 4208);
PAINT MONO (-6677 4208);
FORCEPROP 2 LAST CDS_LIB standard
J 0
(-6675 4200);
DISPLAY INVISIBLE (-6675 4200);
FORCEPROP 1 LAST BODY_TYPE PLUMBING
J 0
(-6675 4150);
DISPLAY 0.574468 (-6675 4150);
PAINT GREEN (-6675 4150);
DISPLAY INVISIBLE (-6675 4150);
FORCEPROP 1 LAST HDL_TAP TRUE
J 0
(-6350 4075);
DISPLAY 0.574468 (-6350 4075);
PAINT GREEN (-6350 4075);
DISPLAY INVISIBLE (-6350 4075);
FORCEPROP 1 LAST PATH I467
J 0
(-6677 4200);
DISPLAY 0.872340 (-6677 4200);
PAINT GREEN (-6677 4200);
DISPLAY INVISIBLE (-6677 4200);
FORCEADD TAP..6
(-6675 4300);
FORCEPROP 3 LASTPIN (-6625 4300) SIG_NAME GMI_CPU0_G2_CPU1_G0_TX_DN<1>
J 0
(-6615 4310);
DISPLAY 0.659574 (-6615 4310);
PAINT MONO (-6615 4310);
DISPLAY INVISIBLE (-6615 4310);
FORCEPROP 1 LASTPIN (-6625 4300) BN 1
J 0
(-6677 4308);
DISPLAY 0.489362 (-6677 4308);
PAINT MONO (-6677 4308);
FORCEPROP 2 LAST CDS_LIB standard
J 0
(-6675 4300);
DISPLAY INVISIBLE (-6675 4300);
FORCEPROP 1 LAST BODY_TYPE PLUMBING
J 0
(-6675 4250);
DISPLAY 0.574468 (-6675 4250);
PAINT GREEN (-6675 4250);
DISPLAY INVISIBLE (-6675 4250);
FORCEPROP 1 LAST HDL_TAP TRUE
J 0
(-6350 4175);
DISPLAY 0.574468 (-6350 4175);
PAINT GREEN (-6350 4175);
DISPLAY INVISIBLE (-6350 4175);
FORCEPROP 1 LAST PATH I468
J 0
(-6677 4300);
DISPLAY 0.872340 (-6677 4300);
PAINT GREEN (-6677 4300);
DISPLAY INVISIBLE (-6677 4300);
FORCEADD OFFPAGE..1
(-7725 5925);
FORCEPROP 2 LASTPIN (-7675 5925) SIG_NAME GMI_CPU0_G2_CPU1_G0_TX_DN<0:15>
J 0
(-7685 5935);
DISPLAY 0.489362 (-7685 5935);
FORCEPROP 2 LAST $XR0 23 
J 0
(-7946 5925);
DISPLAY 0.638298 (-7946 5925);
PAINT MONO (-7946 5925);
FORCEPROP 2 LAST CDS_LIB standard
J 0
(-7725 5925);
DISPLAY INVISIBLE (-7725 5925);
FORCEPROP 1 LAST OFFPAGE TRUE
J 0
(-7400 5800);
DISPLAY 0.872340 (-7400 5800);
PAINT GREEN (-7400 5800);
DISPLAY INVISIBLE (-7400 5800);
FORCEPROP 1 LAST COMMENT_BODY TRUE
J 0
(-7600 5825);
DISPLAY 0.872340 (-7600 5825);
PAINT GREEN (-7600 5825);
DISPLAY INVISIBLE (-7600 5825);
FORCEPROP 2 LAST PATH I469
J 0
(-7925 5975);
DISPLAY 1.021277 (-7925 5975);
DISPLAY INVISIBLE (-7925 5975);
FORCEADD TAP..6
(-6650 2875);
FORCEPROP 3 LASTPIN (-6600 2875) SIG_NAME GMI_CPU0_G3_CPU1_G1_TX_DN<14>
J 0
(-6590 2885);
DISPLAY 0.659574 (-6590 2885);
PAINT MONO (-6590 2885);
DISPLAY INVISIBLE (-6590 2885);
FORCEPROP 1 LASTPIN (-6600 2875) BN 14
J 0
(-6652 2883);
DISPLAY 0.489362 (-6652 2883);
PAINT MONO (-6652 2883);
FORCEPROP 2 LAST CDS_LIB mstr_standard
J 0
(-6650 2875);
DISPLAY INVISIBLE (-6650 2875);
FORCEPROP 1 LAST BODY_TYPE PLUMBING
J 0
(-6650 2825);
DISPLAY 0.574468 (-6650 2825);
PAINT GREEN (-6650 2825);
DISPLAY INVISIBLE (-6650 2825);
FORCEPROP 1 LAST HDL_TAP TRUE
J 0
(-6325 2750);
DISPLAY 0.574468 (-6325 2750);
PAINT GREEN (-6325 2750);
DISPLAY INVISIBLE (-6325 2750);
FORCEPROP 1 LAST PATH I470
J 0
(-6652 2875);
DISPLAY 0.872340 (-6652 2875);
PAINT GREEN (-6652 2875);
DISPLAY INVISIBLE (-6652 2875);
FORCEADD TAP..6
(-6650 2975);
FORCEPROP 3 LASTPIN (-6600 2975) SIG_NAME GMI_CPU0_G3_CPU1_G1_TX_DN<15>
J 0
(-6590 2985);
DISPLAY 0.659574 (-6590 2985);
PAINT MONO (-6590 2985);
DISPLAY INVISIBLE (-6590 2985);
FORCEPROP 1 LASTPIN (-6600 2975) BN 15
J 0
(-6652 2983);
DISPLAY 0.489362 (-6652 2983);
PAINT MONO (-6652 2983);
FORCEPROP 2 LAST CDS_LIB mstr_standard
J 0
(-6650 2975);
DISPLAY INVISIBLE (-6650 2975);
FORCEPROP 1 LAST BODY_TYPE PLUMBING
J 0
(-6650 2925);
DISPLAY 0.574468 (-6650 2925);
PAINT GREEN (-6650 2925);
DISPLAY INVISIBLE (-6650 2925);
FORCEPROP 1 LAST HDL_TAP TRUE
J 0
(-6325 2850);
DISPLAY 0.574468 (-6325 2850);
PAINT GREEN (-6325 2850);
DISPLAY INVISIBLE (-6325 2850);
FORCEPROP 1 LAST PATH I471
J 0
(-6652 2975);
DISPLAY 0.872340 (-6652 2975);
PAINT GREEN (-6652 2975);
DISPLAY INVISIBLE (-6652 2975);
FORCEADD TAP..6
(-6650 2775);
FORCEPROP 3 LASTPIN (-6600 2775) SIG_NAME GMI_CPU0_G3_CPU1_G1_TX_DN<13>
J 0
(-6590 2785);
DISPLAY 0.659574 (-6590 2785);
PAINT MONO (-6590 2785);
DISPLAY INVISIBLE (-6590 2785);
FORCEPROP 1 LASTPIN (-6600 2775) BN 13
J 0
(-6652 2783);
DISPLAY 0.489362 (-6652 2783);
PAINT MONO (-6652 2783);
FORCEPROP 2 LAST CDS_LIB standard
J 0
(-6650 2775);
DISPLAY INVISIBLE (-6650 2775);
FORCEPROP 1 LAST BODY_TYPE PLUMBING
J 0
(-6650 2725);
DISPLAY 0.574468 (-6650 2725);
PAINT GREEN (-6650 2725);
DISPLAY INVISIBLE (-6650 2725);
FORCEPROP 1 LAST HDL_TAP TRUE
J 0
(-6325 2650);
DISPLAY 0.574468 (-6325 2650);
PAINT GREEN (-6325 2650);
DISPLAY INVISIBLE (-6325 2650);
FORCEPROP 1 LAST PATH I472
J 0
(-6652 2775);
DISPLAY 0.872340 (-6652 2775);
PAINT GREEN (-6652 2775);
DISPLAY INVISIBLE (-6652 2775);
FORCEADD TAP..6
(-6650 2675);
FORCEPROP 3 LASTPIN (-6600 2675) SIG_NAME GMI_CPU0_G3_CPU1_G1_TX_DN<12>
J 0
(-6590 2685);
DISPLAY 0.659574 (-6590 2685);
PAINT MONO (-6590 2685);
DISPLAY INVISIBLE (-6590 2685);
FORCEPROP 1 LASTPIN (-6600 2675) BN 12
J 0
(-6652 2683);
DISPLAY 0.489362 (-6652 2683);
PAINT MONO (-6652 2683);
FORCEPROP 2 LAST CDS_LIB standard
J 0
(-6650 2675);
DISPLAY INVISIBLE (-6650 2675);
FORCEPROP 1 LAST BODY_TYPE PLUMBING
J 0
(-6650 2625);
DISPLAY 0.574468 (-6650 2625);
PAINT GREEN (-6650 2625);
DISPLAY INVISIBLE (-6650 2625);
FORCEPROP 1 LAST HDL_TAP TRUE
J 0
(-6325 2550);
DISPLAY 0.574468 (-6325 2550);
PAINT GREEN (-6325 2550);
DISPLAY INVISIBLE (-6325 2550);
FORCEPROP 1 LAST PATH I473
J 0
(-6652 2675);
DISPLAY 0.872340 (-6652 2675);
PAINT GREEN (-6652 2675);
DISPLAY INVISIBLE (-6652 2675);
FORCEADD TAP..6
(-6650 2475);
FORCEPROP 3 LASTPIN (-6600 2475) SIG_NAME GMI_CPU0_G3_CPU1_G1_TX_DN<10>
J 0
(-6590 2485);
DISPLAY 0.659574 (-6590 2485);
PAINT MONO (-6590 2485);
DISPLAY INVISIBLE (-6590 2485);
FORCEPROP 1 LASTPIN (-6600 2475) BN 10
J 0
(-6652 2483);
DISPLAY 0.489362 (-6652 2483);
PAINT MONO (-6652 2483);
FORCEPROP 2 LAST CDS_LIB standard
J 0
(-6650 2475);
DISPLAY INVISIBLE (-6650 2475);
FORCEPROP 1 LAST BODY_TYPE PLUMBING
J 0
(-6650 2425);
DISPLAY 0.574468 (-6650 2425);
PAINT GREEN (-6650 2425);
DISPLAY INVISIBLE (-6650 2425);
FORCEPROP 1 LAST HDL_TAP TRUE
J 0
(-6325 2350);
DISPLAY 0.574468 (-6325 2350);
PAINT GREEN (-6325 2350);
DISPLAY INVISIBLE (-6325 2350);
FORCEPROP 1 LAST PATH I474
J 0
(-6652 2475);
DISPLAY 0.872340 (-6652 2475);
PAINT GREEN (-6652 2475);
DISPLAY INVISIBLE (-6652 2475);
FORCEADD TAP..6
(-6650 2575);
FORCEPROP 3 LASTPIN (-6600 2575) SIG_NAME GMI_CPU0_G3_CPU1_G1_TX_DN<11>
J 0
(-6590 2585);
DISPLAY 0.659574 (-6590 2585);
PAINT MONO (-6590 2585);
DISPLAY INVISIBLE (-6590 2585);
FORCEPROP 1 LASTPIN (-6600 2575) BN 11
J 0
(-6652 2583);
DISPLAY 0.489362 (-6652 2583);
PAINT MONO (-6652 2583);
FORCEPROP 2 LAST CDS_LIB standard
J 0
(-6650 2575);
DISPLAY INVISIBLE (-6650 2575);
FORCEPROP 1 LAST BODY_TYPE PLUMBING
J 0
(-6650 2525);
DISPLAY 0.574468 (-6650 2525);
PAINT GREEN (-6650 2525);
DISPLAY INVISIBLE (-6650 2525);
FORCEPROP 1 LAST HDL_TAP TRUE
J 0
(-6325 2450);
DISPLAY 0.574468 (-6325 2450);
PAINT GREEN (-6325 2450);
DISPLAY INVISIBLE (-6325 2450);
FORCEPROP 1 LAST PATH I475
J 0
(-6652 2575);
DISPLAY 0.872340 (-6652 2575);
PAINT GREEN (-6652 2575);
DISPLAY INVISIBLE (-6652 2575);
FORCEADD TAP..6
(-6650 2375);
FORCEPROP 3 LASTPIN (-6600 2375) SIG_NAME GMI_CPU0_G3_CPU1_G1_TX_DN<9>
J 0
(-6590 2385);
DISPLAY 0.659574 (-6590 2385);
PAINT MONO (-6590 2385);
DISPLAY INVISIBLE (-6590 2385);
FORCEPROP 1 LASTPIN (-6600 2375) BN 9
J 0
(-6652 2383);
DISPLAY 0.489362 (-6652 2383);
PAINT MONO (-6652 2383);
FORCEPROP 2 LAST CDS_LIB standard
J 0
(-6650 2375);
DISPLAY INVISIBLE (-6650 2375);
FORCEPROP 1 LAST BODY_TYPE PLUMBING
J 0
(-6650 2325);
DISPLAY 0.574468 (-6650 2325);
PAINT GREEN (-6650 2325);
DISPLAY INVISIBLE (-6650 2325);
FORCEPROP 1 LAST HDL_TAP TRUE
J 0
(-6325 2250);
DISPLAY 0.574468 (-6325 2250);
PAINT GREEN (-6325 2250);
DISPLAY INVISIBLE (-6325 2250);
FORCEPROP 1 LAST PATH I476
J 0
(-6652 2375);
DISPLAY 0.872340 (-6652 2375);
PAINT GREEN (-6652 2375);
DISPLAY INVISIBLE (-6652 2375);
FORCEADD TAP..6
(-6650 2275);
FORCEPROP 3 LASTPIN (-6600 2275) SIG_NAME GMI_CPU0_G3_CPU1_G1_TX_DN<8>
J 0
(-6590 2285);
DISPLAY 0.659574 (-6590 2285);
PAINT MONO (-6590 2285);
DISPLAY INVISIBLE (-6590 2285);
FORCEPROP 1 LASTPIN (-6600 2275) BN 8
J 0
(-6652 2283);
DISPLAY 0.489362 (-6652 2283);
PAINT MONO (-6652 2283);
FORCEPROP 2 LAST CDS_LIB standard
J 0
(-6650 2275);
DISPLAY INVISIBLE (-6650 2275);
FORCEPROP 1 LAST BODY_TYPE PLUMBING
J 0
(-6650 2225);
DISPLAY 0.574468 (-6650 2225);
PAINT GREEN (-6650 2225);
DISPLAY INVISIBLE (-6650 2225);
FORCEPROP 1 LAST HDL_TAP TRUE
J 0
(-6325 2150);
DISPLAY 0.574468 (-6325 2150);
PAINT GREEN (-6325 2150);
DISPLAY INVISIBLE (-6325 2150);
FORCEPROP 1 LAST PATH I477
J 0
(-6652 2275);
DISPLAY 0.872340 (-6652 2275);
PAINT GREEN (-6652 2275);
DISPLAY INVISIBLE (-6652 2275);
FORCEADD TAP..6
(-6650 2175);
FORCEPROP 3 LASTPIN (-6600 2175) SIG_NAME GMI_CPU0_G3_CPU1_G1_TX_DN<7>
J 0
(-6590 2185);
DISPLAY 0.659574 (-6590 2185);
PAINT MONO (-6590 2185);
DISPLAY INVISIBLE (-6590 2185);
FORCEPROP 1 LASTPIN (-6600 2175) BN 7
J 0
(-6652 2183);
DISPLAY 0.489362 (-6652 2183);
PAINT MONO (-6652 2183);
FORCEPROP 2 LAST CDS_LIB standard
J 0
(-6650 2175);
DISPLAY INVISIBLE (-6650 2175);
FORCEPROP 1 LAST BODY_TYPE PLUMBING
J 0
(-6650 2125);
DISPLAY 0.574468 (-6650 2125);
PAINT GREEN (-6650 2125);
DISPLAY INVISIBLE (-6650 2125);
FORCEPROP 1 LAST HDL_TAP TRUE
J 0
(-6325 2050);
DISPLAY 0.574468 (-6325 2050);
PAINT GREEN (-6325 2050);
DISPLAY INVISIBLE (-6325 2050);
FORCEPROP 1 LAST PATH I478
J 0
(-6652 2175);
DISPLAY 0.872340 (-6652 2175);
PAINT GREEN (-6652 2175);
DISPLAY INVISIBLE (-6652 2175);
FORCEADD TAP..6
(-6650 1975);
FORCEPROP 3 LASTPIN (-6600 1975) SIG_NAME GMI_CPU0_G3_CPU1_G1_TX_DN<5>
J 0
(-6590 1985);
DISPLAY 0.659574 (-6590 1985);
PAINT MONO (-6590 1985);
DISPLAY INVISIBLE (-6590 1985);
FORCEPROP 1 LASTPIN (-6600 1975) BN 5
J 0
(-6652 1983);
DISPLAY 0.489362 (-6652 1983);
PAINT MONO (-6652 1983);
FORCEPROP 2 LAST CDS_LIB standard
J 0
(-6650 1975);
DISPLAY INVISIBLE (-6650 1975);
FORCEPROP 1 LAST BODY_TYPE PLUMBING
J 0
(-6650 1925);
DISPLAY 0.574468 (-6650 1925);
PAINT GREEN (-6650 1925);
DISPLAY INVISIBLE (-6650 1925);
FORCEPROP 1 LAST HDL_TAP TRUE
J 0
(-6325 1850);
DISPLAY 0.574468 (-6325 1850);
PAINT GREEN (-6325 1850);
DISPLAY INVISIBLE (-6325 1850);
FORCEPROP 1 LAST PATH I479
J 0
(-6652 1975);
DISPLAY 0.872340 (-6652 1975);
PAINT GREEN (-6652 1975);
DISPLAY INVISIBLE (-6652 1975);
FORCEADD TAP..6
(-6650 2075);
FORCEPROP 3 LASTPIN (-6600 2075) SIG_NAME GMI_CPU0_G3_CPU1_G1_TX_DN<6>
J 0
(-6590 2085);
DISPLAY 0.659574 (-6590 2085);
PAINT MONO (-6590 2085);
DISPLAY INVISIBLE (-6590 2085);
FORCEPROP 1 LASTPIN (-6600 2075) BN 6
J 0
(-6652 2083);
DISPLAY 0.489362 (-6652 2083);
PAINT MONO (-6652 2083);
FORCEPROP 2 LAST CDS_LIB standard
J 0
(-6650 2075);
DISPLAY INVISIBLE (-6650 2075);
FORCEPROP 1 LAST BODY_TYPE PLUMBING
J 0
(-6650 2025);
DISPLAY 0.574468 (-6650 2025);
PAINT GREEN (-6650 2025);
DISPLAY INVISIBLE (-6650 2025);
FORCEPROP 1 LAST HDL_TAP TRUE
J 0
(-6325 1950);
DISPLAY 0.574468 (-6325 1950);
PAINT GREEN (-6325 1950);
DISPLAY INVISIBLE (-6325 1950);
FORCEPROP 1 LAST PATH I480
J 0
(-6652 2075);
DISPLAY 0.872340 (-6652 2075);
PAINT GREEN (-6652 2075);
DISPLAY INVISIBLE (-6652 2075);
FORCEADD TAP..6
(-6650 1875);
FORCEPROP 3 LASTPIN (-6600 1875) SIG_NAME GMI_CPU0_G3_CPU1_G1_TX_DN<4>
J 0
(-6590 1885);
DISPLAY 0.659574 (-6590 1885);
PAINT MONO (-6590 1885);
DISPLAY INVISIBLE (-6590 1885);
FORCEPROP 1 LASTPIN (-6600 1875) BN 4
J 0
(-6652 1883);
DISPLAY 0.489362 (-6652 1883);
PAINT MONO (-6652 1883);
FORCEPROP 2 LAST CDS_LIB standard
J 0
(-6650 1875);
DISPLAY INVISIBLE (-6650 1875);
FORCEPROP 1 LAST BODY_TYPE PLUMBING
J 0
(-6650 1825);
DISPLAY 0.574468 (-6650 1825);
PAINT GREEN (-6650 1825);
DISPLAY INVISIBLE (-6650 1825);
FORCEPROP 1 LAST HDL_TAP TRUE
J 0
(-6325 1750);
DISPLAY 0.574468 (-6325 1750);
PAINT GREEN (-6325 1750);
DISPLAY INVISIBLE (-6325 1750);
FORCEPROP 1 LAST PATH I481
J 0
(-6652 1875);
DISPLAY 0.872340 (-6652 1875);
PAINT GREEN (-6652 1875);
DISPLAY INVISIBLE (-6652 1875);
FORCEADD TAP..6
(-6650 1775);
FORCEPROP 3 LASTPIN (-6600 1775) SIG_NAME GMI_CPU0_G3_CPU1_G1_TX_DN<3>
J 0
(-6590 1785);
DISPLAY 0.659574 (-6590 1785);
PAINT MONO (-6590 1785);
DISPLAY INVISIBLE (-6590 1785);
FORCEPROP 1 LASTPIN (-6600 1775) BN 3
J 0
(-6652 1783);
DISPLAY 0.489362 (-6652 1783);
PAINT MONO (-6652 1783);
FORCEPROP 2 LAST CDS_LIB standard
J 0
(-6650 1775);
DISPLAY INVISIBLE (-6650 1775);
FORCEPROP 1 LAST BODY_TYPE PLUMBING
J 0
(-6650 1725);
DISPLAY 0.574468 (-6650 1725);
PAINT GREEN (-6650 1725);
DISPLAY INVISIBLE (-6650 1725);
FORCEPROP 1 LAST HDL_TAP TRUE
J 0
(-6325 1650);
DISPLAY 0.574468 (-6325 1650);
PAINT GREEN (-6325 1650);
DISPLAY INVISIBLE (-6325 1650);
FORCEPROP 1 LAST PATH I482
J 0
(-6652 1775);
DISPLAY 0.872340 (-6652 1775);
PAINT GREEN (-6652 1775);
DISPLAY INVISIBLE (-6652 1775);
FORCEADD TAP..6
(-6650 1675);
FORCEPROP 3 LASTPIN (-6600 1675) SIG_NAME GMI_CPU0_G3_CPU1_G1_TX_DN<2>
J 0
(-6590 1685);
DISPLAY 0.659574 (-6590 1685);
PAINT MONO (-6590 1685);
DISPLAY INVISIBLE (-6590 1685);
FORCEPROP 1 LASTPIN (-6600 1675) BN 2
J 0
(-6652 1683);
DISPLAY 0.489362 (-6652 1683);
PAINT MONO (-6652 1683);
FORCEPROP 2 LAST CDS_LIB standard
J 0
(-6650 1675);
DISPLAY INVISIBLE (-6650 1675);
FORCEPROP 1 LAST BODY_TYPE PLUMBING
J 0
(-6650 1625);
DISPLAY 0.574468 (-6650 1625);
PAINT GREEN (-6650 1625);
DISPLAY INVISIBLE (-6650 1625);
FORCEPROP 1 LAST HDL_TAP TRUE
J 0
(-6325 1550);
DISPLAY 0.574468 (-6325 1550);
PAINT GREEN (-6325 1550);
DISPLAY INVISIBLE (-6325 1550);
FORCEPROP 1 LAST PATH I483
J 0
(-6652 1675);
DISPLAY 0.872340 (-6652 1675);
PAINT GREEN (-6652 1675);
DISPLAY INVISIBLE (-6652 1675);
FORCEADD TAP..6
(-6650 1575);
FORCEPROP 3 LASTPIN (-6600 1575) SIG_NAME GMI_CPU0_G3_CPU1_G1_TX_DN<1>
J 0
(-6590 1585);
DISPLAY 0.659574 (-6590 1585);
PAINT MONO (-6590 1585);
DISPLAY INVISIBLE (-6590 1585);
FORCEPROP 1 LASTPIN (-6600 1575) BN 1
J 0
(-6652 1583);
DISPLAY 0.489362 (-6652 1583);
PAINT MONO (-6652 1583);
FORCEPROP 2 LAST CDS_LIB standard
J 0
(-6650 1575);
DISPLAY INVISIBLE (-6650 1575);
FORCEPROP 1 LAST BODY_TYPE PLUMBING
J 0
(-6650 1525);
DISPLAY 0.574468 (-6650 1525);
PAINT GREEN (-6650 1525);
DISPLAY INVISIBLE (-6650 1525);
FORCEPROP 1 LAST HDL_TAP TRUE
J 0
(-6325 1450);
DISPLAY 0.574468 (-6325 1450);
PAINT GREEN (-6325 1450);
DISPLAY INVISIBLE (-6325 1450);
FORCEPROP 1 LAST PATH I484
J 0
(-6652 1575);
DISPLAY 0.872340 (-6652 1575);
PAINT GREEN (-6652 1575);
DISPLAY INVISIBLE (-6652 1575);
FORCEADD TAP..6
(-6650 1475);
FORCEPROP 3 LASTPIN (-6600 1475) SIG_NAME GMI_CPU0_G3_CPU1_G1_TX_DN<0>
J 0
(-6590 1485);
DISPLAY 0.659574 (-6590 1485);
PAINT MONO (-6590 1485);
DISPLAY INVISIBLE (-6590 1485);
FORCEPROP 1 LASTPIN (-6600 1475) BN 0
J 0
(-6652 1483);
DISPLAY 0.489362 (-6652 1483);
PAINT MONO (-6652 1483);
FORCEPROP 2 LAST CDS_LIB standard
J 0
(-6650 1475);
DISPLAY INVISIBLE (-6650 1475);
FORCEPROP 1 LAST BODY_TYPE PLUMBING
J 0
(-6650 1425);
DISPLAY 0.574468 (-6650 1425);
PAINT GREEN (-6650 1425);
DISPLAY INVISIBLE (-6650 1425);
FORCEPROP 1 LAST HDL_TAP TRUE
J 0
(-6325 1350);
DISPLAY 0.574468 (-6325 1350);
PAINT GREEN (-6325 1350);
DISPLAY INVISIBLE (-6325 1350);
FORCEPROP 1 LAST PATH I485
J 0
(-6652 1475);
DISPLAY 0.872340 (-6652 1475);
PAINT GREEN (-6652 1475);
DISPLAY INVISIBLE (-6652 1475);
FORCEADD OFFPAGE..1
(-7600 3200);
FORCEPROP 2 LASTPIN (-7550 3200) SIG_NAME GMI_CPU0_G3_CPU1_G1_TX_DN<0:15>
J 0
(-7535 3210);
DISPLAY 0.489362 (-7535 3210);
FORCEPROP 2 LAST $XR0 23 
J 0
(-7821 3200);
DISPLAY 0.638298 (-7821 3200);
PAINT MONO (-7821 3200);
FORCEPROP 2 LAST CDS_LIB standard
J 0
(-7600 3200);
DISPLAY INVISIBLE (-7600 3200);
FORCEPROP 1 LAST OFFPAGE TRUE
J 0
(-7275 3075);
DISPLAY 0.872340 (-7275 3075);
PAINT GREEN (-7275 3075);
DISPLAY INVISIBLE (-7275 3075);
FORCEPROP 1 LAST COMMENT_BODY TRUE
J 0
(-7475 3100);
DISPLAY 0.872340 (-7475 3100);
PAINT GREEN (-7475 3100);
DISPLAY INVISIBLE (-7475 3100);
FORCEPROP 2 LAST PATH I486
J 0
(-7800 3250);
DISPLAY 1.021277 (-7800 3250);
DISPLAY INVISIBLE (-7800 3250);
FORCEADD OFFPAGE..2
(-1800 3200);
FORCEPROP 2 LAST $XR0 23 
J 0
(-1611 3200);
DISPLAY 0.638298 (-1611 3200);
PAINT MONO (-1611 3200);
FORCEPROP 2 LAST CDS_LIB standard
J 0
(-1800 3200);
DISPLAY INVISIBLE (-1800 3200);
FORCEPROP 1 LAST OFFPAGE TRUE
J 0
(-1475 3075);
DISPLAY 0.872340 (-1475 3075);
PAINT GREEN (-1475 3075);
DISPLAY INVISIBLE (-1475 3075);
FORCEPROP 1 LAST COMMENT_BODY TRUE
J 0
(-1845 3105);
DISPLAY 0.872340 (-1845 3105);
PAINT GREEN (-1845 3105);
DISPLAY INVISIBLE (-1845 3105);
FORCEPROP 2 LAST PATH I487
J 0
(-1600 3250);
DISPLAY 1.021277 (-1600 3250);
DISPLAY INVISIBLE (-1600 3250);
FORCEADD TAP..6
R 2
(-2925 2975);
FORCEPROP 3 LASTPIN (-2975 2975) SIG_NAME GMI_CPU1_G1_CPU0_G3_TX_DN<15>
J 0
(-2965 2985);
DISPLAY 0.659574 (-2965 2985);
PAINT MONO (-2965 2985);
DISPLAY INVISIBLE (-2965 2985);
FORCEPROP 1 LASTPIN (-2975 2975) BN 15
J 2
(-2923 2983);
DISPLAY 0.489362 (-2923 2983);
PAINT MONO (-2923 2983);
FORCEPROP 2 LAST BOM_COST IO_SLOT
J 0
(-3425 3075);
DISPLAY 0.829787 (-3425 3075);
DISPLAY INVISIBLE (-3425 3075);
FORCEPROP 2 LAST CDS_LIB mstr_standard
J 0
(-2925 2975);
DISPLAY INVISIBLE (-2925 2975);
FORCEPROP 1 LAST BODY_TYPE PLUMBING
J 2
(-2925 2925);
DISPLAY 0.702128 (-2925 2925);
PAINT GREEN (-2925 2925);
DISPLAY INVISIBLE (-2925 2925);
FORCEPROP 1 LAST HDL_TAP TRUE
J 2
(-3250 2850);
DISPLAY 0.702128 (-3250 2850);
PAINT GREEN (-3250 2850);
DISPLAY INVISIBLE (-3250 2850);
FORCEPROP 1 LAST PATH I488
J 2
(-2923 2975);
DISPLAY 0.872340 (-2923 2975);
PAINT GREEN (-2923 2975);
DISPLAY INVISIBLE (-2923 2975);
FORCEPROP 2 LAST ROOM RISER1
J 0
(-3425 3025);
DISPLAY 0.829787 (-3425 3025);
PAINT RED (-3425 3025);
DISPLAY INVISIBLE (-3425 3025);
FORCEADD TAP..6
R 2
(-2925 2875);
FORCEPROP 3 LASTPIN (-2975 2875) SIG_NAME GMI_CPU1_G1_CPU0_G3_TX_DN<14>
J 0
(-2965 2885);
DISPLAY 0.659574 (-2965 2885);
PAINT MONO (-2965 2885);
DISPLAY INVISIBLE (-2965 2885);
FORCEPROP 1 LASTPIN (-2975 2875) BN 14
J 2
(-2923 2883);
DISPLAY 0.489362 (-2923 2883);
PAINT MONO (-2923 2883);
FORCEPROP 2 LAST CDS_LIB mstr_standard
J 0
(-2925 2875);
DISPLAY INVISIBLE (-2925 2875);
FORCEPROP 2 LAST BOM_COST IO_SLOT
J 0
(-3425 2975);
DISPLAY 0.829787 (-3425 2975);
DISPLAY INVISIBLE (-3425 2975);
FORCEPROP 1 LAST BODY_TYPE PLUMBING
J 2
(-2925 2825);
DISPLAY 0.702128 (-2925 2825);
PAINT GREEN (-2925 2825);
DISPLAY INVISIBLE (-2925 2825);
FORCEPROP 1 LAST HDL_TAP TRUE
J 2
(-3250 2750);
DISPLAY 0.702128 (-3250 2750);
PAINT GREEN (-3250 2750);
DISPLAY INVISIBLE (-3250 2750);
FORCEPROP 1 LAST PATH I489
J 2
(-2923 2875);
DISPLAY 0.872340 (-2923 2875);
PAINT GREEN (-2923 2875);
DISPLAY INVISIBLE (-2923 2875);
FORCEPROP 2 LAST ROOM RISER1
J 0
(-3425 2925);
DISPLAY 0.829787 (-3425 2925);
PAINT RED (-3425 2925);
DISPLAY INVISIBLE (-3425 2925);
FORCEADD TAP..6
R 2
(-2925 2775);
FORCEPROP 3 LASTPIN (-2975 2775) SIG_NAME GMI_CPU1_G1_CPU0_G3_TX_DN<13>
J 0
(-2965 2785);
DISPLAY 0.659574 (-2965 2785);
PAINT MONO (-2965 2785);
DISPLAY INVISIBLE (-2965 2785);
FORCEPROP 1 LASTPIN (-2975 2775) BN 13
J 2
(-2923 2783);
DISPLAY 0.489362 (-2923 2783);
PAINT MONO (-2923 2783);
FORCEPROP 2 LAST CDS_LIB standard
J 0
(-2925 2775);
DISPLAY INVISIBLE (-2925 2775);
FORCEPROP 2 LAST BOM_COST IO_SLOT
J 0
(-3425 2875);
DISPLAY 0.829787 (-3425 2875);
DISPLAY INVISIBLE (-3425 2875);
FORCEPROP 1 LAST BODY_TYPE PLUMBING
J 2
(-2925 2725);
DISPLAY 0.702128 (-2925 2725);
PAINT GREEN (-2925 2725);
DISPLAY INVISIBLE (-2925 2725);
FORCEPROP 1 LAST HDL_TAP TRUE
J 2
(-3250 2650);
DISPLAY 0.702128 (-3250 2650);
PAINT GREEN (-3250 2650);
DISPLAY INVISIBLE (-3250 2650);
FORCEPROP 1 LAST PATH I490
J 2
(-2923 2775);
DISPLAY 0.872340 (-2923 2775);
PAINT GREEN (-2923 2775);
DISPLAY INVISIBLE (-2923 2775);
FORCEPROP 2 LAST ROOM RISER1
J 0
(-3425 2825);
DISPLAY 0.829787 (-3425 2825);
PAINT RED (-3425 2825);
DISPLAY INVISIBLE (-3425 2825);
FORCEADD TAP..6
R 2
(-2925 2675);
FORCEPROP 3 LASTPIN (-2975 2675) SIG_NAME GMI_CPU1_G1_CPU0_G3_TX_DN<12>
J 0
(-2965 2685);
DISPLAY 0.659574 (-2965 2685);
PAINT MONO (-2965 2685);
DISPLAY INVISIBLE (-2965 2685);
FORCEPROP 1 LASTPIN (-2975 2675) BN 12
J 2
(-2923 2683);
DISPLAY 0.489362 (-2923 2683);
PAINT MONO (-2923 2683);
FORCEPROP 2 LAST CDS_LIB standard
J 0
(-2925 2675);
DISPLAY INVISIBLE (-2925 2675);
FORCEPROP 2 LAST BOM_COST IO_SLOT
J 0
(-3425 2775);
DISPLAY 0.829787 (-3425 2775);
DISPLAY INVISIBLE (-3425 2775);
FORCEPROP 1 LAST BODY_TYPE PLUMBING
J 2
(-2925 2625);
DISPLAY 0.702128 (-2925 2625);
PAINT GREEN (-2925 2625);
DISPLAY INVISIBLE (-2925 2625);
FORCEPROP 1 LAST HDL_TAP TRUE
J 2
(-3250 2550);
DISPLAY 0.702128 (-3250 2550);
PAINT GREEN (-3250 2550);
DISPLAY INVISIBLE (-3250 2550);
FORCEPROP 1 LAST PATH I491
J 2
(-2923 2675);
DISPLAY 0.872340 (-2923 2675);
PAINT GREEN (-2923 2675);
DISPLAY INVISIBLE (-2923 2675);
FORCEPROP 2 LAST ROOM RISER1
J 0
(-3425 2725);
DISPLAY 0.829787 (-3425 2725);
PAINT RED (-3425 2725);
DISPLAY INVISIBLE (-3425 2725);
FORCEADD TAP..6
R 2
(-2925 2575);
FORCEPROP 3 LASTPIN (-2975 2575) SIG_NAME GMI_CPU1_G1_CPU0_G3_TX_DN<11>
J 0
(-2965 2585);
DISPLAY 0.659574 (-2965 2585);
PAINT MONO (-2965 2585);
DISPLAY INVISIBLE (-2965 2585);
FORCEPROP 1 LASTPIN (-2975 2575) BN 11
J 2
(-2923 2583);
DISPLAY 0.489362 (-2923 2583);
PAINT MONO (-2923 2583);
FORCEPROP 2 LAST CDS_LIB standard
J 0
(-2925 2575);
DISPLAY INVISIBLE (-2925 2575);
FORCEPROP 2 LAST BOM_COST IO_SLOT
J 0
(-3425 2675);
DISPLAY 0.829787 (-3425 2675);
DISPLAY INVISIBLE (-3425 2675);
FORCEPROP 1 LAST BODY_TYPE PLUMBING
J 2
(-2925 2525);
DISPLAY 0.702128 (-2925 2525);
PAINT GREEN (-2925 2525);
DISPLAY INVISIBLE (-2925 2525);
FORCEPROP 1 LAST HDL_TAP TRUE
J 2
(-3250 2450);
DISPLAY 0.702128 (-3250 2450);
PAINT GREEN (-3250 2450);
DISPLAY INVISIBLE (-3250 2450);
FORCEPROP 1 LAST PATH I492
J 2
(-2923 2575);
DISPLAY 0.872340 (-2923 2575);
PAINT GREEN (-2923 2575);
DISPLAY INVISIBLE (-2923 2575);
FORCEPROP 2 LAST ROOM RISER1
J 0
(-3425 2625);
DISPLAY 0.829787 (-3425 2625);
PAINT RED (-3425 2625);
DISPLAY INVISIBLE (-3425 2625);
FORCEADD TAP..6
R 2
(-2925 2475);
FORCEPROP 3 LASTPIN (-2975 2475) SIG_NAME GMI_CPU1_G1_CPU0_G3_TX_DN<10>
J 0
(-2965 2485);
DISPLAY 0.659574 (-2965 2485);
PAINT MONO (-2965 2485);
DISPLAY INVISIBLE (-2965 2485);
FORCEPROP 1 LASTPIN (-2975 2475) BN 10
J 2
(-2923 2483);
DISPLAY 0.489362 (-2923 2483);
PAINT MONO (-2923 2483);
FORCEPROP 2 LAST CDS_LIB standard
J 0
(-2925 2475);
DISPLAY INVISIBLE (-2925 2475);
FORCEPROP 2 LAST BOM_COST IO_SLOT
J 0
(-3425 2575);
DISPLAY 0.829787 (-3425 2575);
DISPLAY INVISIBLE (-3425 2575);
FORCEPROP 1 LAST BODY_TYPE PLUMBING
J 2
(-2925 2425);
DISPLAY 0.702128 (-2925 2425);
PAINT GREEN (-2925 2425);
DISPLAY INVISIBLE (-2925 2425);
FORCEPROP 1 LAST HDL_TAP TRUE
J 2
(-3250 2350);
DISPLAY 0.702128 (-3250 2350);
PAINT GREEN (-3250 2350);
DISPLAY INVISIBLE (-3250 2350);
FORCEPROP 1 LAST PATH I493
J 2
(-2923 2475);
DISPLAY 0.872340 (-2923 2475);
PAINT GREEN (-2923 2475);
DISPLAY INVISIBLE (-2923 2475);
FORCEPROP 2 LAST ROOM RISER1
J 0
(-3425 2525);
DISPLAY 0.829787 (-3425 2525);
PAINT RED (-3425 2525);
DISPLAY INVISIBLE (-3425 2525);
FORCEADD TAP..6
R 2
(-2925 2375);
FORCEPROP 3 LASTPIN (-2975 2375) SIG_NAME GMI_CPU1_G1_CPU0_G3_TX_DN<9>
J 0
(-2965 2385);
DISPLAY 0.659574 (-2965 2385);
PAINT MONO (-2965 2385);
DISPLAY INVISIBLE (-2965 2385);
FORCEPROP 1 LASTPIN (-2975 2375) BN 9
J 2
(-2923 2383);
DISPLAY 0.489362 (-2923 2383);
PAINT MONO (-2923 2383);
FORCEPROP 2 LAST CDS_LIB standard
J 0
(-2925 2375);
DISPLAY INVISIBLE (-2925 2375);
FORCEPROP 2 LAST BOM_COST IO_SLOT
J 0
(-3425 2475);
DISPLAY 0.829787 (-3425 2475);
DISPLAY INVISIBLE (-3425 2475);
FORCEPROP 1 LAST BODY_TYPE PLUMBING
J 2
(-2925 2325);
DISPLAY 0.702128 (-2925 2325);
PAINT GREEN (-2925 2325);
DISPLAY INVISIBLE (-2925 2325);
FORCEPROP 1 LAST HDL_TAP TRUE
J 2
(-3250 2250);
DISPLAY 0.702128 (-3250 2250);
PAINT GREEN (-3250 2250);
DISPLAY INVISIBLE (-3250 2250);
FORCEPROP 1 LAST PATH I494
J 2
(-2923 2375);
DISPLAY 0.872340 (-2923 2375);
PAINT GREEN (-2923 2375);
DISPLAY INVISIBLE (-2923 2375);
FORCEPROP 2 LAST ROOM RISER1
J 0
(-3425 2425);
DISPLAY 0.829787 (-3425 2425);
PAINT RED (-3425 2425);
DISPLAY INVISIBLE (-3425 2425);
FORCEADD TAP..6
R 2
(-2925 2275);
FORCEPROP 3 LASTPIN (-2975 2275) SIG_NAME GMI_CPU1_G1_CPU0_G3_TX_DN<8>
J 0
(-2965 2285);
DISPLAY 0.659574 (-2965 2285);
PAINT MONO (-2965 2285);
DISPLAY INVISIBLE (-2965 2285);
FORCEPROP 1 LASTPIN (-2975 2275) BN 8
J 2
(-2923 2283);
DISPLAY 0.489362 (-2923 2283);
PAINT MONO (-2923 2283);
FORCEPROP 2 LAST CDS_LIB standard
J 0
(-2925 2275);
DISPLAY INVISIBLE (-2925 2275);
FORCEPROP 2 LAST BOM_COST IO_SLOT
J 0
(-3425 2375);
DISPLAY 0.829787 (-3425 2375);
DISPLAY INVISIBLE (-3425 2375);
FORCEPROP 1 LAST BODY_TYPE PLUMBING
J 2
(-2925 2225);
DISPLAY 0.702128 (-2925 2225);
PAINT GREEN (-2925 2225);
DISPLAY INVISIBLE (-2925 2225);
FORCEPROP 1 LAST HDL_TAP TRUE
J 2
(-3250 2150);
DISPLAY 0.702128 (-3250 2150);
PAINT GREEN (-3250 2150);
DISPLAY INVISIBLE (-3250 2150);
FORCEPROP 1 LAST PATH I495
J 2
(-2923 2275);
DISPLAY 0.872340 (-2923 2275);
PAINT GREEN (-2923 2275);
DISPLAY INVISIBLE (-2923 2275);
FORCEPROP 2 LAST ROOM RISER1
J 0
(-3425 2325);
DISPLAY 0.829787 (-3425 2325);
PAINT RED (-3425 2325);
DISPLAY INVISIBLE (-3425 2325);
FORCEADD TAP..6
R 2
(-2925 2175);
FORCEPROP 3 LASTPIN (-2975 2175) SIG_NAME GMI_CPU1_G1_CPU0_G3_TX_DN<7>
J 0
(-2965 2185);
DISPLAY 0.659574 (-2965 2185);
PAINT MONO (-2965 2185);
DISPLAY INVISIBLE (-2965 2185);
FORCEPROP 1 LASTPIN (-2975 2175) BN 7
J 2
(-2923 2183);
DISPLAY 0.489362 (-2923 2183);
PAINT MONO (-2923 2183);
FORCEPROP 2 LAST CDS_LIB standard
J 0
(-2925 2175);
DISPLAY INVISIBLE (-2925 2175);
FORCEPROP 2 LAST BOM_COST IO_SLOT
J 0
(-3425 2275);
DISPLAY 0.829787 (-3425 2275);
DISPLAY INVISIBLE (-3425 2275);
FORCEPROP 1 LAST BODY_TYPE PLUMBING
J 2
(-2925 2125);
DISPLAY 0.702128 (-2925 2125);
PAINT GREEN (-2925 2125);
DISPLAY INVISIBLE (-2925 2125);
FORCEPROP 1 LAST HDL_TAP TRUE
J 2
(-3250 2050);
DISPLAY 0.702128 (-3250 2050);
PAINT GREEN (-3250 2050);
DISPLAY INVISIBLE (-3250 2050);
FORCEPROP 1 LAST PATH I496
J 2
(-2923 2175);
DISPLAY 0.872340 (-2923 2175);
PAINT GREEN (-2923 2175);
DISPLAY INVISIBLE (-2923 2175);
FORCEPROP 2 LAST ROOM RISER1
J 0
(-3425 2225);
DISPLAY 0.829787 (-3425 2225);
PAINT RED (-3425 2225);
DISPLAY INVISIBLE (-3425 2225);
FORCEADD TAP..6
R 2
(-2925 1975);
FORCEPROP 3 LASTPIN (-2975 1975) SIG_NAME GMI_CPU1_G1_CPU0_G3_TX_DN<5>
J 0
(-2965 1985);
DISPLAY 0.659574 (-2965 1985);
PAINT MONO (-2965 1985);
DISPLAY INVISIBLE (-2965 1985);
FORCEPROP 1 LASTPIN (-2975 1975) BN 5
J 2
(-2923 1983);
DISPLAY 0.489362 (-2923 1983);
PAINT MONO (-2923 1983);
FORCEPROP 2 LAST CDS_LIB standard
J 0
(-2925 1975);
DISPLAY INVISIBLE (-2925 1975);
FORCEPROP 2 LAST BOM_COST IO_SLOT
J 0
(-3425 2075);
DISPLAY 0.829787 (-3425 2075);
DISPLAY INVISIBLE (-3425 2075);
FORCEPROP 1 LAST BODY_TYPE PLUMBING
J 2
(-2925 1925);
DISPLAY 0.702128 (-2925 1925);
PAINT GREEN (-2925 1925);
DISPLAY INVISIBLE (-2925 1925);
FORCEPROP 1 LAST HDL_TAP TRUE
J 2
(-3250 1850);
DISPLAY 0.702128 (-3250 1850);
PAINT GREEN (-3250 1850);
DISPLAY INVISIBLE (-3250 1850);
FORCEPROP 1 LAST PATH I497
J 2
(-2923 1975);
DISPLAY 0.872340 (-2923 1975);
PAINT GREEN (-2923 1975);
DISPLAY INVISIBLE (-2923 1975);
FORCEPROP 2 LAST ROOM RISER1
J 0
(-3425 2025);
DISPLAY 0.829787 (-3425 2025);
PAINT RED (-3425 2025);
DISPLAY INVISIBLE (-3425 2025);
FORCEADD TAP..6
R 2
(-2925 2075);
FORCEPROP 3 LASTPIN (-2975 2075) SIG_NAME GMI_CPU1_G1_CPU0_G3_TX_DN<6>
J 0
(-2965 2085);
DISPLAY 0.659574 (-2965 2085);
PAINT MONO (-2965 2085);
DISPLAY INVISIBLE (-2965 2085);
FORCEPROP 1 LASTPIN (-2975 2075) BN 6
J 2
(-2923 2083);
DISPLAY 0.489362 (-2923 2083);
PAINT MONO (-2923 2083);
FORCEPROP 2 LAST CDS_LIB standard
J 0
(-2925 2075);
DISPLAY INVISIBLE (-2925 2075);
FORCEPROP 2 LAST BOM_COST IO_SLOT
J 0
(-3425 2175);
DISPLAY 0.829787 (-3425 2175);
DISPLAY INVISIBLE (-3425 2175);
FORCEPROP 1 LAST BODY_TYPE PLUMBING
J 2
(-2925 2025);
DISPLAY 0.702128 (-2925 2025);
PAINT GREEN (-2925 2025);
DISPLAY INVISIBLE (-2925 2025);
FORCEPROP 1 LAST HDL_TAP TRUE
J 2
(-3250 1950);
DISPLAY 0.702128 (-3250 1950);
PAINT GREEN (-3250 1950);
DISPLAY INVISIBLE (-3250 1950);
FORCEPROP 1 LAST PATH I498
J 2
(-2923 2075);
DISPLAY 0.872340 (-2923 2075);
PAINT GREEN (-2923 2075);
DISPLAY INVISIBLE (-2923 2075);
FORCEPROP 2 LAST ROOM RISER1
J 0
(-3425 2125);
DISPLAY 0.829787 (-3425 2125);
PAINT RED (-3425 2125);
DISPLAY INVISIBLE (-3425 2125);
FORCEADD TAP..6
R 2
(-2925 1775);
FORCEPROP 3 LASTPIN (-2975 1775) SIG_NAME GMI_CPU1_G1_CPU0_G3_TX_DN<3>
J 0
(-2965 1785);
DISPLAY 0.659574 (-2965 1785);
PAINT MONO (-2965 1785);
DISPLAY INVISIBLE (-2965 1785);
FORCEPROP 1 LASTPIN (-2975 1775) BN 3
J 2
(-2923 1783);
DISPLAY 0.489362 (-2923 1783);
PAINT MONO (-2923 1783);
FORCEPROP 2 LAST CDS_LIB standard
J 0
(-2925 1775);
DISPLAY INVISIBLE (-2925 1775);
FORCEPROP 2 LAST BOM_COST IO_SLOT
J 0
(-3425 1875);
DISPLAY 0.829787 (-3425 1875);
DISPLAY INVISIBLE (-3425 1875);
FORCEPROP 1 LAST BODY_TYPE PLUMBING
J 2
(-2925 1725);
DISPLAY 0.702128 (-2925 1725);
PAINT GREEN (-2925 1725);
DISPLAY INVISIBLE (-2925 1725);
FORCEPROP 1 LAST HDL_TAP TRUE
J 2
(-3250 1650);
DISPLAY 0.702128 (-3250 1650);
PAINT GREEN (-3250 1650);
DISPLAY INVISIBLE (-3250 1650);
FORCEPROP 1 LAST PATH I499
J 2
(-2923 1775);
DISPLAY 0.872340 (-2923 1775);
PAINT GREEN (-2923 1775);
DISPLAY INVISIBLE (-2923 1775);
FORCEPROP 2 LAST ROOM RISER1
J 0
(-3425 1825);
DISPLAY 0.829787 (-3425 1825);
PAINT RED (-3425 1825);
DISPLAY INVISIBLE (-3425 1825);
FORCEADD TAP..6
R 2
(-2925 1875);
FORCEPROP 3 LASTPIN (-2975 1875) SIG_NAME GMI_CPU1_G1_CPU0_G3_TX_DN<4>
J 0
(-2965 1885);
DISPLAY 0.659574 (-2965 1885);
PAINT MONO (-2965 1885);
DISPLAY INVISIBLE (-2965 1885);
FORCEPROP 1 LASTPIN (-2975 1875) BN 4
J 2
(-2923 1883);
DISPLAY 0.489362 (-2923 1883);
PAINT MONO (-2923 1883);
FORCEPROP 2 LAST CDS_LIB standard
J 0
(-2925 1875);
DISPLAY INVISIBLE (-2925 1875);
FORCEPROP 2 LAST BOM_COST IO_SLOT
J 0
(-3425 1975);
DISPLAY 0.829787 (-3425 1975);
DISPLAY INVISIBLE (-3425 1975);
FORCEPROP 1 LAST BODY_TYPE PLUMBING
J 2
(-2925 1825);
DISPLAY 0.702128 (-2925 1825);
PAINT GREEN (-2925 1825);
DISPLAY INVISIBLE (-2925 1825);
FORCEPROP 1 LAST HDL_TAP TRUE
J 2
(-3250 1750);
DISPLAY 0.702128 (-3250 1750);
PAINT GREEN (-3250 1750);
DISPLAY INVISIBLE (-3250 1750);
FORCEPROP 1 LAST PATH I500
J 2
(-2923 1875);
DISPLAY 0.872340 (-2923 1875);
PAINT GREEN (-2923 1875);
DISPLAY INVISIBLE (-2923 1875);
FORCEPROP 2 LAST ROOM RISER1
J 0
(-3425 1925);
DISPLAY 0.829787 (-3425 1925);
PAINT RED (-3425 1925);
DISPLAY INVISIBLE (-3425 1925);
FORCEADD TAP..6
R 2
(-2925 1675);
FORCEPROP 3 LASTPIN (-2975 1675) SIG_NAME GMI_CPU1_G1_CPU0_G3_TX_DN<2>
J 0
(-2965 1685);
DISPLAY 0.659574 (-2965 1685);
PAINT MONO (-2965 1685);
DISPLAY INVISIBLE (-2965 1685);
FORCEPROP 1 LASTPIN (-2975 1675) BN 2
J 2
(-2923 1683);
DISPLAY 0.489362 (-2923 1683);
PAINT MONO (-2923 1683);
FORCEPROP 2 LAST CDS_LIB standard
J 0
(-2925 1675);
DISPLAY INVISIBLE (-2925 1675);
FORCEPROP 2 LAST BOM_COST IO_SLOT
J 0
(-3425 1775);
DISPLAY 0.829787 (-3425 1775);
DISPLAY INVISIBLE (-3425 1775);
FORCEPROP 1 LAST BODY_TYPE PLUMBING
J 2
(-2925 1625);
DISPLAY 0.702128 (-2925 1625);
PAINT GREEN (-2925 1625);
DISPLAY INVISIBLE (-2925 1625);
FORCEPROP 1 LAST HDL_TAP TRUE
J 2
(-3250 1550);
DISPLAY 0.702128 (-3250 1550);
PAINT GREEN (-3250 1550);
DISPLAY INVISIBLE (-3250 1550);
FORCEPROP 1 LAST PATH I501
J 2
(-2923 1675);
DISPLAY 0.872340 (-2923 1675);
PAINT GREEN (-2923 1675);
DISPLAY INVISIBLE (-2923 1675);
FORCEPROP 2 LAST ROOM RISER1
J 0
(-3425 1725);
DISPLAY 0.829787 (-3425 1725);
PAINT RED (-3425 1725);
DISPLAY INVISIBLE (-3425 1725);
FORCEADD TAP..6
R 2
(-2925 1575);
FORCEPROP 3 LASTPIN (-2975 1575) SIG_NAME GMI_CPU1_G1_CPU0_G3_TX_DN<1>
J 0
(-2965 1585);
DISPLAY 0.659574 (-2965 1585);
PAINT MONO (-2965 1585);
DISPLAY INVISIBLE (-2965 1585);
FORCEPROP 1 LASTPIN (-2975 1575) BN 1
J 2
(-2923 1583);
DISPLAY 0.489362 (-2923 1583);
PAINT MONO (-2923 1583);
FORCEPROP 2 LAST BOM_COST IO_SLOT
J 0
(-3425 1675);
DISPLAY 0.829787 (-3425 1675);
DISPLAY INVISIBLE (-3425 1675);
FORCEPROP 2 LAST CDS_LIB standard
J 0
(-2925 1575);
DISPLAY INVISIBLE (-2925 1575);
FORCEPROP 1 LAST BODY_TYPE PLUMBING
J 2
(-2925 1525);
DISPLAY 0.702128 (-2925 1525);
PAINT GREEN (-2925 1525);
DISPLAY INVISIBLE (-2925 1525);
FORCEPROP 1 LAST HDL_TAP TRUE
J 2
(-3250 1450);
DISPLAY 0.702128 (-3250 1450);
PAINT GREEN (-3250 1450);
DISPLAY INVISIBLE (-3250 1450);
FORCEPROP 1 LAST PATH I502
J 2
(-2923 1575);
DISPLAY 0.872340 (-2923 1575);
PAINT GREEN (-2923 1575);
DISPLAY INVISIBLE (-2923 1575);
FORCEPROP 2 LAST ROOM RISER1
J 0
(-3425 1625);
DISPLAY 0.829787 (-3425 1625);
PAINT RED (-3425 1625);
DISPLAY INVISIBLE (-3425 1625);
FORCEADD TAP..6
R 2
(-2925 1475);
FORCEPROP 3 LASTPIN (-2975 1475) SIG_NAME GMI_CPU1_G1_CPU0_G3_TX_DN<0>
J 0
(-2965 1485);
DISPLAY 0.659574 (-2965 1485);
PAINT MONO (-2965 1485);
DISPLAY INVISIBLE (-2965 1485);
FORCEPROP 1 LASTPIN (-2975 1475) BN 0
J 2
(-2923 1483);
DISPLAY 0.489362 (-2923 1483);
PAINT MONO (-2923 1483);
FORCEPROP 2 LAST CDS_LIB standard
J 0
(-2925 1475);
DISPLAY INVISIBLE (-2925 1475);
FORCEPROP 2 LAST BOM_COST IO_SLOT
J 0
(-3425 1575);
DISPLAY 0.829787 (-3425 1575);
DISPLAY INVISIBLE (-3425 1575);
FORCEPROP 1 LAST BODY_TYPE PLUMBING
J 2
(-2925 1425);
DISPLAY 0.702128 (-2925 1425);
PAINT GREEN (-2925 1425);
DISPLAY INVISIBLE (-2925 1425);
FORCEPROP 1 LAST HDL_TAP TRUE
J 2
(-3250 1350);
DISPLAY 0.702128 (-3250 1350);
PAINT GREEN (-3250 1350);
DISPLAY INVISIBLE (-3250 1350);
FORCEPROP 1 LAST PATH I503
J 2
(-2923 1475);
DISPLAY 0.872340 (-2923 1475);
PAINT GREEN (-2923 1475);
DISPLAY INVISIBLE (-2923 1475);
FORCEPROP 2 LAST ROOM RISER1
J 0
(-3425 1525);
DISPLAY 0.829787 (-3425 1525);
PAINT RED (-3425 1525);
DISPLAY INVISIBLE (-3425 1525);
FORCEADD QUANTA_TITLE_BLOCK_C..1
(-100 100);
FORCEPROP 0 LAST CDS_CON_LAST_MODIFIED Fri Mar 11 14:52:35 2022
J 0
(-1985 115);
DISPLAY INVISIBLE (-1985 115);
FORCEPROP 1 LAST CUSTOM_TXT_CDS <CON_LAST_MODIFIED>
J 0
(-1985 115);
DISPLAY 0.978723 (-1985 115);
FORCEPROP 2 LAST CUSTOM_TXT_CDS <XR_PAGE_TITLE>
J 0
(-7990 5350);
DISPLAY 0.638298 (-7990 5350);
PAINT PINK (-7990 5350);
DISPLAY INVISIBLE (-7990 5350);
FORCEPROP 1 LAST CUSTOM_TXT_CDS <NAME_2>
J 0
(-3275 150);
FORCEPROP 1 LAST CUSTOM_TXT_CDS <NAME_1>
J 0
(-3275 275);
FORCEPROP 1 LAST CUSTOM_TXT_CDS <Q_NUMBER>
J 0
(-1503 203);
DISPLAY 1.212766 (-1503 203);
FORCEPROP 1 LAST CUSTOM_TXT_CDS <Q_PROJ>
J 0
(-2482 202);
DISPLAY 1.212766 (-2482 202);
FORCEPROP 1 LAST CUSTOM_TXT_CDS <Q_REV>
J 0
(-284 203);
DISPLAY 1.212766 (-284 203);
FORCEPROP 1 LAST CUSTOM_TXT_CDS <CON_PAGE_NUM> OF <CON_TOTAL_PAGES>
J 0
(-546 118);
DISPLAY 0.978723 (-546 118);
FORCEPROP 1 LAST Q_DEPT BU9
J 1
(-3863 149);
DISPLAY 1.957447 (-3863 149);
PAINT GREEN (-3863 149);
FORCEPROP 1 LAST Q_TITLE CPU1 PCIE G0/G1
J 0
(-9375 175);
DISPLAY 2.446809 (-9375 175);
PAINT GREEN (-9375 175);
FORCEPROP 2 LAST PAGE_BORDER TRUE
J 0
(-7990 5350);
DISPLAY 0.638298 (-7990 5350);
PAINT PINK (-7990 5350);
DISPLAY INVISIBLE (-7990 5350);
FORCEPROP 1 LAST CDS_LMAN_SYM_OUTLINE -9475,6775,100,-125
J 0
(-100 100);
DISPLAY 0.468085 (-100 100);
PAINT GREEN (-100 100);
DISPLAY INVISIBLE (-100 100);
FORCEPROP 2 LAST CDS_LIB pure_quanta
J 0
(-100 100);
DISPLAY INVISIBLE (-100 100);
FORCEPROP 1 LAST COMMENT_BODY TRUE
J 0
(-88 87);
DISPLAY 0.978723 (-88 87);
PAINT GREEN (-88 87);
DISPLAY INVISIBLE (-88 87);
FORCEPROP 2 LAST CDS_XR_PAGE_TITLE CR-49 : @T6G_MB_LIB.T6G(SCH_1):PAGE49
J 0
(-7990 5350);
DISPLAY 0.638298 (-7990 5350);
PAINT PINK (-7990 5350);
DISPLAY INVISIBLE (-7990 5350);
WIRE 17 -1 (-2900 5725)(-2900 5625);
WIRE 17 -1 (-2900 5925)(-2900 5725);
WIRE 17 -1 (-2900 5625)(-2900 5525);
WIRE 17 -1 (-2900 5525)(-2900 5425);
WIRE 17 -1 (-2900 5925)(-1875 5925);
FORCEPROP 2 LAST SIG_NAME GMI_CPU1_G0_CPU0_G2_TX_DN<0:15>
J 0
(-2860 5935);
DISPLAY 0.489362 (-2860 5935);
WIRE 17 -1 (-2900 5425)(-2900 5325);
WIRE 17 -1 (-2900 5325)(-2900 5225);
WIRE 17 -1 (-2900 5225)(-2900 5125);
WIRE 17 -1 (-2900 5125)(-2900 5025);
WIRE 17 -1 (-2900 5025)(-2900 4925);
WIRE 17 -1 (-2900 4925)(-2900 4825);
WIRE 17 -1 (-2900 4825)(-2900 4725);
WIRE 17 -1 (-2900 4725)(-2900 4625);
WIRE 17 -1 (-2900 4625)(-2900 4525);
WIRE 17 -1 (-2900 4525)(-2900 4425);
WIRE 17 -1 (-2900 4425)(-2900 4325);
WIRE 17 -1 (-2900 4325)(-2900 4225);
WIRE 17 -1 (-3050 5775)(-3050 5675);
WIRE 17 -1 (-3050 5975)(-3050 5775);
WIRE 17 -1 (-3050 5675)(-3050 5575);
WIRE 17 -1 (-3050 5575)(-3050 5475);
WIRE 17 -1 (-3050 5975)(-1875 5975);
FORCEPROP 2 LAST SIG_NAME GMI_CPU1_G0_CPU0_G2_TX_DP<0:15>
J 0
(-2860 5985);
DISPLAY 0.489362 (-2860 5985);
WIRE 17 -1 (-3050 5475)(-3050 5375);
WIRE 17 -1 (-3050 5375)(-3050 5275);
WIRE 17 -1 (-3050 5275)(-3050 5175);
WIRE 17 -1 (-3050 5175)(-3050 5075);
WIRE 17 -1 (-3050 5075)(-3050 4975);
WIRE 17 -1 (-3050 4975)(-3050 4875);
WIRE 17 -1 (-3050 4875)(-3050 4775);
WIRE 17 -1 (-3050 4775)(-3050 4675);
WIRE 17 -1 (-3050 4675)(-3050 4575);
WIRE 17 -1 (-3050 4575)(-3050 4475);
WIRE 17 -1 (-3050 4475)(-3050 4375);
WIRE 17 -1 (-3050 4375)(-3050 4275);
WIRE 17 -1 (-2875 2100)(-2875 2000);
WIRE 17 -1 (-2875 2200)(-2875 2100);
WIRE 17 -1 (-2875 2000)(-2875 1900);
WIRE 17 -1 (-2875 1900)(-2875 1800);
WIRE 17 -1 (-2875 2300)(-2875 2200);
WIRE 17 -1 (-2875 2400)(-2875 2300);
WIRE 17 -1 (-2875 1800)(-2875 1700);
WIRE 17 -1 (-2875 1700)(-2875 1600);
WIRE 17 -1 (-2875 2500)(-2875 2400);
WIRE 17 -1 (-2875 2600)(-2875 2500);
WIRE 17 -1 (-2875 1600)(-2875 1500);
WIRE 17 -1 (-2875 2700)(-2875 2600);
WIRE 17 -1 (-2875 2800)(-2875 2700);
WIRE 17 -1 (-2875 2900)(-2875 2800);
WIRE 17 -1 (-2875 3000)(-2875 2900);
WIRE 17 -1 (-2875 3200)(-2875 3000);
WIRE 17 -1 (-2875 3200)(-1850 3200);
FORCEPROP 2 LAST SIG_NAME GMI_CPU1_G1_CPU0_G3_TX_DN<0:15>
J 0
(-2910 3210);
DISPLAY 0.489362 (-2910 3210);
WIRE 17 -1 (-3025 3050)(-3025 2950);
WIRE 17 -1 (-3025 3250)(-3025 3050);
WIRE 17 -1 (-3025 2950)(-3025 2850);
WIRE 17 -1 (-3025 2850)(-3025 2750);
WIRE 17 -1 (-3025 3250)(-1850 3250);
FORCEPROP 2 LAST SIG_NAME GMI_CPU1_G1_CPU0_G3_TX_DP<0:15>
J 0
(-2910 3260);
DISPLAY 0.489362 (-2910 3260);
WIRE 17 -1 (-3025 2750)(-3025 2650);
WIRE 17 -1 (-3025 2650)(-3025 2550);
WIRE 17 -1 (-3025 2550)(-3025 2450);
WIRE 17 -1 (-3025 2450)(-3025 2350);
WIRE 17 -1 (-3025 2350)(-3025 2250);
WIRE 17 -1 (-3025 2250)(-3025 2150);
WIRE 17 -1 (-3025 2150)(-3025 2050);
WIRE 17 -1 (-3025 2050)(-3025 1950);
WIRE 17 -1 (-3025 1950)(-3025 1850);
WIRE 17 -1 (-3025 1850)(-3025 1750);
WIRE 17 -1 (-3025 1750)(-3025 1650);
WIRE 17 -1 (-3025 1650)(-3025 1550);
WIRE 17 -1 (-6725 5725)(-6725 5925);
WIRE 17 -1 (-6725 5625)(-6725 5725);
WIRE 17 -1 (-6725 5925)(-7675 5925);
WIRE 17 -1 (-6725 5525)(-6725 5625);
WIRE 17 -1 (-6725 5425)(-6725 5525);
WIRE 17 -1 (-6725 5325)(-6725 5425);
WIRE 17 -1 (-6725 5225)(-6725 5325);
WIRE 17 -1 (-6725 5125)(-6725 5225);
WIRE 17 -1 (-6725 5025)(-6725 5125);
WIRE 17 -1 (-6725 4925)(-6725 5025);
WIRE 17 -1 (-6725 4825)(-6725 4925);
WIRE 17 -1 (-6725 4725)(-6725 4825);
WIRE 17 -1 (-6725 4625)(-6725 4725);
WIRE 17 -1 (-6725 4525)(-6725 4625);
WIRE 17 -1 (-6725 4425)(-6725 4525);
WIRE 17 -1 (-6725 4325)(-6725 4425);
WIRE 17 -1 (-6725 4225)(-6725 4325);
WIRE 17 -1 (-6575 5775)(-6575 5975);
WIRE 17 -1 (-6575 5675)(-6575 5775);
WIRE 17 -1 (-6575 5975)(-7675 5975);
FORCEPROP 2 LAST SIG_NAME GMI_CPU0_G2_CPU1_G0_TX_DP<0:15>
J 0
(-7685 5985);
DISPLAY 0.489362 (-7685 5985);
WIRE 17 -1 (-6575 5575)(-6575 5675);
WIRE 17 -1 (-6575 5475)(-6575 5575);
WIRE 17 -1 (-6575 5375)(-6575 5475);
WIRE 17 -1 (-6575 5275)(-6575 5375);
WIRE 17 -1 (-6575 5175)(-6575 5275);
WIRE 17 -1 (-6575 5075)(-6575 5175);
WIRE 17 -1 (-6575 4975)(-6575 5075);
WIRE 17 -1 (-6575 4875)(-6575 4975);
WIRE 17 -1 (-6575 4775)(-6575 4875);
WIRE 17 -1 (-6575 4675)(-6575 4775);
WIRE 17 -1 (-6575 4575)(-6575 4675);
WIRE 17 -1 (-6575 4475)(-6575 4575);
WIRE 17 -1 (-6575 4375)(-6575 4475);
WIRE 17 -1 (-6575 4275)(-6575 4375);
WIRE 17 -1 (-6550 1550)(-6550 1650);
WIRE 17 -1 (-6550 1650)(-6550 1750);
WIRE 17 -1 (-6550 1750)(-6550 1850);
WIRE 17 -1 (-6550 1850)(-6550 1950);
WIRE 17 -1 (-6550 1950)(-6550 2050);
WIRE 17 -1 (-6550 2050)(-6550 2150);
WIRE 17 -1 (-6550 2150)(-6550 2250);
WIRE 17 -1 (-6550 2250)(-6550 2350);
WIRE 17 -1 (-6550 2350)(-6550 2450);
WIRE 17 -1 (-6550 2450)(-6550 2550);
WIRE 17 -1 (-6550 2550)(-6550 2650);
WIRE 17 -1 (-6550 2650)(-6550 2750);
WIRE 17 -1 (-6550 2750)(-6550 2850);
WIRE 17 -1 (-6550 2850)(-6550 2950);
WIRE 17 -1 (-6550 2950)(-6550 3050);
WIRE 17 -1 (-6550 3050)(-6550 3250);
WIRE 17 -1 (-6550 3250)(-7550 3250);
WIRE 17 -1 (-6700 1500)(-6700 1600);
WIRE 17 -1 (-6700 1600)(-6700 1700);
WIRE 17 -1 (-6700 1700)(-6700 1800);
WIRE 17 -1 (-6700 1800)(-6700 1900);
WIRE 17 -1 (-6700 1900)(-6700 2000);
WIRE 17 -1 (-6700 2000)(-6700 2100);
WIRE 17 -1 (-6700 2100)(-6700 2200);
WIRE 17 -1 (-6700 2200)(-6700 2300);
WIRE 17 -1 (-6700 2300)(-6700 2400);
WIRE 17 -1 (-6700 2400)(-6700 2500);
WIRE 17 -1 (-6700 2500)(-6700 2600);
WIRE 17 -1 (-6700 2600)(-6700 2700);
WIRE 17 -1 (-6700 2700)(-6700 2800);
WIRE 17 -1 (-6700 2800)(-6700 2900);
WIRE 17 -1 (-6700 2900)(-6700 3000);
WIRE 17 -1 (-6700 3000)(-6700 3200);
WIRE 17 -1 (-6700 3200)(-7550 3200);
WIRE 16 -1 (-6600 2275)(-6000 2275);
WIRE 16 -1 (-6600 2375)(-6000 2375);
WIRE 16 -1 (-6600 2475)(-6000 2475);
WIRE 16 -1 (-6450 2325)(-6000 2325);
WIRE 16 -1 (-6600 2575)(-6000 2575);
WIRE 16 -1 (-6450 2425)(-6000 2425);
WIRE 16 -1 (-6600 2675)(-6000 2675);
WIRE 16 -1 (-6450 2525)(-6000 2525);
WIRE 16 -1 (-6600 2775)(-6000 2775);
WIRE 16 -1 (-6450 2625)(-6000 2625);
WIRE 16 -1 (-6600 2875)(-6000 2875);
WIRE 16 -1 (-6450 2725)(-6000 2725);
WIRE 16 -1 (-6600 2975)(-6000 2975);
WIRE 16 -1 (-6450 2825)(-6000 2825);
WIRE 16 -1 (-6450 2925)(-6000 2925);
WIRE 16 -1 (-6450 3025)(-6000 3025);
WIRE 16 -1 (-6600 2175)(-6000 2175);
WIRE 16 -1 (-6600 2075)(-6000 2075);
WIRE 16 -1 (-6600 1975)(-6000 1975);
WIRE 16 -1 (-6600 1875)(-6000 1875);
WIRE 16 -1 (-6600 1775)(-6000 1775);
WIRE 16 -1 (-6600 1675)(-6000 1675);
WIRE 16 -1 (-6600 1575)(-6000 1575);
WIRE 16 -1 (-6600 1475)(-6000 1475);
WIRE 16 -1 (-6450 2225)(-6000 2225);
WIRE 16 -1 (-6450 2125)(-6000 2125);
WIRE 16 -1 (-6450 2025)(-6000 2025);
WIRE 16 -1 (-6450 1925)(-6000 1925);
WIRE 16 -1 (-6450 1825)(-6000 1825);
WIRE 16 -1 (-6450 1725)(-6000 1725);
WIRE 16 -1 (-6450 1625)(-6000 1625);
WIRE 16 -1 (-6450 1525)(-6000 1525);
WIRE 16 -1 (-6475 4250)(-6025 4250);
WIRE 16 -1 (-6475 4350)(-6025 4350);
WIRE 16 -1 (-6475 4450)(-6025 4450);
WIRE 16 -1 (-6475 4550)(-6025 4550);
WIRE 16 -1 (-6475 4650)(-6025 4650);
WIRE 16 -1 (-6475 4750)(-6025 4750);
WIRE 16 -1 (-6475 4850)(-6025 4850);
WIRE 16 -1 (-6475 4950)(-6025 4950);
WIRE 16 -1 (-6475 5050)(-6025 5050);
WIRE 16 -1 (-6475 5150)(-6025 5150);
WIRE 16 -1 (-6475 5250)(-6025 5250);
WIRE 16 -1 (-6475 5350)(-6025 5350);
WIRE 16 -1 (-6475 5450)(-6025 5450);
WIRE 16 -1 (-6475 5550)(-6025 5550);
WIRE 16 -1 (-6475 5650)(-6025 5650);
WIRE 16 -1 (-6475 5750)(-6025 5750);
WIRE 16 -1 (-6625 4200)(-6025 4200);
WIRE 16 -1 (-6625 4300)(-6025 4300);
WIRE 16 -1 (-6625 4400)(-6025 4400);
WIRE 16 -1 (-6625 4500)(-6025 4500);
WIRE 16 -1 (-6625 4600)(-6025 4600);
WIRE 16 -1 (-6625 4700)(-6025 4700);
WIRE 16 -1 (-6625 4800)(-6025 4800);
WIRE 16 -1 (-6625 4900)(-6025 4900);
WIRE 16 -1 (-6625 5000)(-6025 5000);
WIRE 16 -1 (-6625 5100)(-6025 5100);
WIRE 16 -1 (-6625 5200)(-6025 5200);
WIRE 16 -1 (-6625 5300)(-6025 5300);
WIRE 16 -1 (-6625 5400)(-6025 5400);
WIRE 16 -1 (-6625 5500)(-6025 5500);
WIRE 16 -1 (-6625 5600)(-6025 5600);
WIRE 16 -1 (-6625 5700)(-6025 5700);
WIRE 16 -1 (-3500 1525)(-3125 1525);
WIRE 16 -1 (-3500 2025)(-3125 2025);
WIRE 16 -1 (-3500 1925)(-3125 1925);
WIRE 16 -1 (-3500 1825)(-3125 1825);
WIRE 16 -1 (-3500 1725)(-3125 1725);
WIRE 16 -1 (-3500 1625)(-3125 1625);
WIRE 16 -1 (-3500 1975)(-2975 1975);
WIRE 16 -1 (-3500 1875)(-2975 1875);
WIRE 16 -1 (-3500 1775)(-2975 1775);
WIRE 16 -1 (-3500 1675)(-2975 1675);
WIRE 16 -1 (-3500 1575)(-2975 1575);
WIRE 16 -1 (-3500 1475)(-2975 1475);
WIRE 16 -1 (-3500 2325)(-3125 2325);
WIRE 16 -1 (-3500 2425)(-3125 2425);
WIRE 16 -1 (-3500 2525)(-3125 2525);
WIRE 16 -1 (-3500 2225)(-3125 2225);
WIRE 16 -1 (-3500 2125)(-3125 2125);
WIRE 16 -1 (-3500 2625)(-3125 2625);
WIRE 16 -1 (-3500 2725)(-3125 2725);
WIRE 16 -1 (-3500 2825)(-3125 2825);
WIRE 16 -1 (-3500 2925)(-3125 2925);
WIRE 16 -1 (-3500 3025)(-3125 3025);
WIRE 16 -1 (-3500 2275)(-2975 2275);
WIRE 16 -1 (-3500 2375)(-2975 2375);
WIRE 16 -1 (-3500 2475)(-2975 2475);
WIRE 16 -1 (-3500 2575)(-2975 2575);
WIRE 16 -1 (-3500 2675)(-2975 2675);
WIRE 16 -1 (-3500 2775)(-2975 2775);
WIRE 16 -1 (-3500 2875)(-2975 2875);
WIRE 16 -1 (-3500 2975)(-2975 2975);
WIRE 16 -1 (-3500 2175)(-2975 2175);
WIRE 16 -1 (-3500 2075)(-2975 2075);
WIRE 16 -1 (-3525 4250)(-3150 4250);
WIRE 16 -1 (-3525 4350)(-3150 4350);
WIRE 16 -1 (-3525 4450)(-3150 4450);
WIRE 16 -1 (-3525 4550)(-3150 4550);
WIRE 16 -1 (-3525 4650)(-3150 4650);
WIRE 16 -1 (-3525 4750)(-3150 4750);
WIRE 16 -1 (-3525 4850)(-3150 4850);
WIRE 16 -1 (-3525 4950)(-3150 4950);
WIRE 16 -1 (-3525 5050)(-3150 5050);
WIRE 16 -1 (-3525 5150)(-3150 5150);
WIRE 16 -1 (-3525 5250)(-3150 5250);
WIRE 16 -1 (-3525 5350)(-3150 5350);
WIRE 16 -1 (-3525 5450)(-3150 5450);
WIRE 16 -1 (-3525 5550)(-3150 5550);
WIRE 16 -1 (-3525 5650)(-3150 5650);
WIRE 16 -1 (-3525 5750)(-3150 5750);
WIRE 16 -1 (-3525 4200)(-3000 4200);
WIRE 16 -1 (-3525 4300)(-3000 4300);
WIRE 16 -1 (-3525 4400)(-3000 4400);
WIRE 16 -1 (-3525 4500)(-3000 4500);
WIRE 16 -1 (-3525 4600)(-3000 4600);
WIRE 16 -1 (-3525 4700)(-3000 4700);
WIRE 16 -1 (-3525 4800)(-3000 4800);
WIRE 16 -1 (-3525 4900)(-3000 4900);
WIRE 16 -1 (-3525 5000)(-3000 5000);
WIRE 16 -1 (-3525 5100)(-3000 5100);
WIRE 16 -1 (-3525 5200)(-3000 5200);
WIRE 16 -1 (-3525 5300)(-3000 5300);
WIRE 16 -1 (-3525 5400)(-3000 5400);
WIRE 16 -1 (-3525 5500)(-3000 5500);
WIRE 16 -1 (-3525 5600)(-3000 5600);
WIRE 16 -1 (-3525 5700)(-3000 5700);
FORCENOTE
LANE REVERSAL
(-2075 2050) 0;
DISPLAY LEFT (-2075 2050);
DISPLAY 1.595745 (-2075 2050);
FORCENOTE
LANE REVERSAL
(-2050 4775) 0;
DISPLAY LEFT (-2050 4775);
DISPLAY 1.595745 (-2050 4775);
QUIT
